FILE_TYPE = MACRO_DRAWING;
SET COLOR_WIRE YELLOW;
SET COLOR_PROP ORANGE;
SET COLOR_DOT WHITE;
SET COLOR_ARC YELLOW;
SET COLOR_BODY GREEN;
SET COLOR_NOTE PURPLE;
SET PROP_DISPLAY VALUE;
SET PAGE_NUMBER P153;
FORCEADD CYUSB330468LTXI..1
(-4650 3650);
FORCEPROP 1 LAST LOCATION U6001
J 0
(-5125 6375);
DISPLAY 0.723404 (-5125 6375);
PAINT GREEN (-5125 6375);
FORCEPROP 2 LAST SEC 1
J 0
(-5100 6700);
DISPLAY 0.680851 (-5100 6700);
PAINT MONO (-5100 6700);
DISPLAY INVISIBLE (-5100 6700);
FORCEPROP 2 LASTPIN (-4025 5775) $PN 59
J 0
(-4015 5785);
DISPLAY 0.680851 (-4015 5785);
PAINT MONO (-4015 5785);
FORCEPROP 2 LASTPIN (-4025 5725) $PN 60
J 0
(-4015 5735);
DISPLAY 0.680851 (-4015 5735);
PAINT MONO (-4015 5735);
FORCEPROP 2 LASTPIN (-4025 5625) $PN 50
J 0
(-4015 5635);
DISPLAY 0.680851 (-4015 5635);
PAINT MONO (-4015 5635);
FORCEPROP 2 LASTPIN (-4025 5575) $PN 51
J 0
(-4015 5585);
DISPLAY 0.680851 (-4015 5585);
PAINT MONO (-4015 5585);
FORCEPROP 2 LASTPIN (-4025 5475) $PN 48
J 0
(-4015 5485);
DISPLAY 0.680851 (-4015 5485);
PAINT MONO (-4015 5485);
FORCEPROP 2 LASTPIN (-4025 5425) $PN 47
J 0
(-4015 5435);
DISPLAY 0.680851 (-4015 5435);
PAINT MONO (-4015 5435);
FORCEPROP 2 LASTPIN (-4025 4525) $PN 63
J 0
(-4015 4535);
DISPLAY 0.680851 (-4015 4535);
PAINT MONO (-4015 4535);
FORCEPROP 2 LASTPIN (-4025 4475) $PN 62
J 0
(-4015 4485);
DISPLAY 0.680851 (-4015 4485);
PAINT MONO (-4015 4485);
FORCEPROP 2 LASTPIN (-4025 4375) $PN 44
J 0
(-4015 4385);
DISPLAY 0.680851 (-4015 4385);
PAINT MONO (-4015 4385);
FORCEPROP 2 LASTPIN (-4025 4325) $PN 45
J 0
(-4015 4335);
DISPLAY 0.680851 (-4015 4335);
PAINT MONO (-4015 4335);
FORCEPROP 2 LASTPIN (-4025 4225) $PN 42
J 0
(-4015 4235);
DISPLAY 0.680851 (-4015 4235);
PAINT MONO (-4015 4235);
FORCEPROP 2 LASTPIN (-4025 4175) $PN 41
J 0
(-4015 4185);
DISPLAY 0.680851 (-4015 4185);
PAINT MONO (-4015 4185);
FORCEPROP 2 LASTPIN (-4025 3275) $PN 64
J 0
(-4015 3285);
DISPLAY 0.680851 (-4015 3285);
PAINT MONO (-4015 3285);
FORCEPROP 2 LASTPIN (-4025 3225) $PN 65
J 0
(-4015 3235);
DISPLAY 0.680851 (-4015 3235);
PAINT MONO (-4015 3235);
FORCEPROP 2 LASTPIN (-4025 3125) $PN 36
J 0
(-4015 3135);
DISPLAY 0.680851 (-4015 3135);
PAINT MONO (-4015 3135);
FORCEPROP 2 LASTPIN (-4025 3075) $PN 35
J 0
(-4015 3085);
DISPLAY 0.680851 (-4015 3085);
PAINT MONO (-4015 3085);
FORCEPROP 2 LASTPIN (-4025 2975) $PN 39
J 0
(-4015 2985);
DISPLAY 0.680851 (-4015 2985);
PAINT MONO (-4015 2985);
FORCEPROP 2 LASTPIN (-4025 2925) $PN 38
J 0
(-4015 2935);
DISPLAY 0.680851 (-4015 2935);
PAINT MONO (-4015 2935);
FORCEPROP 2 LASTPIN (-4025 2025) $PN 68
J 0
(-4015 2035);
DISPLAY 0.680851 (-4015 2035);
PAINT MONO (-4015 2035);
FORCEPROP 2 LASTPIN (-4025 1975) $PN 67
J 0
(-4015 1985);
DISPLAY 0.680851 (-4015 1985);
PAINT MONO (-4015 1985);
FORCEPROP 2 LASTPIN (-4025 1875) $PN 14
J 0
(-4015 1885);
DISPLAY 0.680851 (-4015 1885);
PAINT MONO (-4015 1885);
FORCEPROP 2 LASTPIN (-4025 1825) $PN 15
J 0
(-4015 1835);
DISPLAY 0.680851 (-4015 1835);
PAINT MONO (-4015 1835);
FORCEPROP 2 LASTPIN (-4025 1725) $PN 12
J 0
(-4015 1735);
DISPLAY 0.680851 (-4015 1735);
PAINT MONO (-4015 1735);
FORCEPROP 2 LASTPIN (-4025 1675) $PN 11
J 0
(-4015 1685);
DISPLAY 0.680851 (-4015 1685);
PAINT MONO (-4015 1685);
FORCEPROP 2 LASTPIN (-4025 1275) $PN TH
J 0
(-4015 1285);
DISPLAY 0.680851 (-4015 1285);
PAINT MONO (-4015 1285);
FORCEPROP 2 LASTPIN (-4025 1325) $PN 40
J 0
(-4015 1335);
DISPLAY 0.680851 (-4015 1335);
PAINT MONO (-4015 1335);
FORCEPROP 2 LASTPIN (-5275 4425) $PN 32
J 2
(-5285 4435);
DISPLAY 0.680851 (-5285 4435);
PAINT MONO (-5285 4435);
FORCEPROP 2 LASTPIN (-5275 4525) $PN 33
J 2
(-5285 4535);
DISPLAY 0.680851 (-5285 4535);
PAINT MONO (-5285 4535);
FORCEPROP 2 LASTPIN (-5275 1575) $PN 23
J 2
(-5285 1585);
DISPLAY 0.680851 (-5285 1585);
PAINT MONO (-5285 1585);
FORCEPROP 2 LASTPIN (-5275 1175) $PN 24
J 2
(-5285 1185);
DISPLAY 0.680851 (-5285 1185);
PAINT MONO (-5285 1185);
FORCEPROP 2 LASTPIN (-5275 3875) $PN 25
J 2
(-5285 3885);
DISPLAY 0.680851 (-5285 3885);
PAINT MONO (-5285 3885);
FORCEPROP 2 LASTPIN (-5275 2925) $PN 30
J 2
(-5285 2935);
DISPLAY 0.680851 (-5285 2935);
PAINT MONO (-5285 2935);
FORCEPROP 2 LASTPIN (-5275 3025) $PN 29
J 2
(-5285 3035);
DISPLAY 0.680851 (-5285 3035);
PAINT MONO (-5285 3035);
FORCEPROP 2 LASTPIN (-5275 2675) $PN 21
J 2
(-5285 2685);
DISPLAY 0.680851 (-5285 2685);
PAINT MONO (-5285 2685);
FORCEPROP 2 LASTPIN (-5275 2775) $PN 22
J 2
(-5285 2785);
DISPLAY 0.680851 (-5285 2785);
PAINT MONO (-5285 2785);
FORCEPROP 2 LASTPIN (-5275 1825) $PN 31
J 2
(-5285 1835);
DISPLAY 0.680851 (-5285 1835);
PAINT MONO (-5285 1835);
FORCEPROP 2 LASTPIN (-5275 4225) $PN 26
J 2
(-5285 4235);
DISPLAY 0.680851 (-5285 4235);
PAINT MONO (-5285 4235);
FORCEPROP 2 LASTPIN (-5275 4125) $PN 2
J 2
(-5285 4135);
DISPLAY 0.680851 (-5285 4135);
PAINT MONO (-5285 4135);
FORCEPROP 2 LASTPIN (-5275 3575) $PN 20
J 2
(-5285 3585);
DISPLAY 0.680851 (-5285 3585);
PAINT MONO (-5285 3585);
FORCEPROP 2 LASTPIN (-5275 5775) $PN 58
J 2
(-5285 5785);
DISPLAY 0.680851 (-5285 5785);
PAINT MONO (-5285 5785);
FORCEPROP 2 LASTPIN (-5275 5725) $PN 57
J 2
(-5285 5735);
DISPLAY 0.680851 (-5285 5735);
PAINT MONO (-5285 5735);
FORCEPROP 2 LASTPIN (-5275 5475) $PN 8
J 2
(-5285 5485);
DISPLAY 0.680851 (-5285 5485);
PAINT MONO (-5285 5485);
FORCEPROP 2 LASTPIN (-5275 5425) $PN 9
J 2
(-5285 5435);
DISPLAY 0.680851 (-5285 5435);
PAINT MONO (-5285 5435);
FORCEPROP 2 LASTPIN (-5275 5625) $PN 5
J 2
(-5285 5635);
DISPLAY 0.680851 (-5285 5635);
PAINT MONO (-5285 5635);
FORCEPROP 2 LASTPIN (-5275 5575) $PN 6
J 2
(-5285 5585);
DISPLAY 0.680851 (-5285 5585);
PAINT MONO (-5285 5585);
FORCEPROP 2 LASTPIN (-4025 6125) $PN 18
J 0
(-4015 6135);
DISPLAY 0.680851 (-4015 6135);
PAINT MONO (-4015 6135);
FORCEPROP 2 LASTPIN (-5275 6125) $PN 17
J 2
(-5285 6135);
DISPLAY 0.680851 (-5285 6135);
PAINT MONO (-5285 6135);
FORCEPROP 2 LASTPIN (-5275 2125) $PN 55
J 2
(-5285 2135);
DISPLAY 0.680851 (-5285 2135);
PAINT MONO (-5285 2135);
FORCEPROP 2 LASTPIN (-5275 2375) $PN 54
J 2
(-5285 2385);
DISPLAY 0.680851 (-5285 2385);
PAINT MONO (-5285 2385);
FORCEPROP 2 LAST PART_TYPE SMLF
J 0
(-5125 6475);
DISPLAY 0.680851 (-5125 6475);
FORCEPROP 1 LAST MATERIAL IC
J 0
(-5116 6275);
DISPLAY 0.723404 (-5116 6275);
PAINT GREEN (-5116 6275);
FORCEPROP 2 LAST ROOM USB3_HUB1_CYP
J 0
(-5125 6525);
DISPLAY 0.680851 (-5125 6525);
PAINT RED (-5125 6525);
FORCEPROP 2 LAST VALUE CYUSB3304-68LTXI
J 0
(-5125 6425);
DISPLAY 0.680851 (-5125 6425);
FORCEPROP 2 LAST SEC_TYPE 
J 0
(-5100 6700);
DISPLAY 0.680851 (-5100 6700);
DISPLAY INVISIBLE (-5100 6700);
FORCEPROP 2 LAST CDS_LIB pure_quanta
J 0
(-4650 3650);
DISPLAY INVISIBLE (-4650 3650);
FORCEPROP 1 LAST CDS_LMAN_SYM_OUTLINE -475,2575,475,-2575
J 0
(-4650 3650);
DISPLAY 0.468085 (-4650 3650);
PAINT GREEN (-4650 3650);
DISPLAY INVISIBLE (-4650 3650);
FORCEPROP 1 LAST NEEDS_NO_SIZE TRUE
J 0
(-4650 3650);
DISPLAY 0.723404 (-4650 3650);
PAINT GREEN (-4650 3650);
DISPLAY INVISIBLE (-4650 3650);
FORCEPROP 1 LAST PATH I1
J 0
(-4650 3650);
DISPLAY 0.723404 (-4650 3650);
PAINT GREEN (-4650 3650);
DISPLAY INVISIBLE (-4650 3650);
FORCEPROP 1 LAST PART_NUMBER AJ033040001
J 0
(-5116 6327);
DISPLAY 0.723404 (-5116 6327);
PAINT GREEN (-5116 6327);
DISPLAY INVISIBLE (-5116 6327);
FORCEADD OFFPAGE..2
(-3000 5475);
FORCEPROP 2 LAST $XR0 180 
J 0
(-2811 5475);
DISPLAY 0.638298 (-2811 5475);
PAINT MONO (-2811 5475);
FORCEPROP 2 LAST CDS_LIB standard
J 2
(-3000 5475);
DISPLAY INVISIBLE (-3000 5475);
FORCEPROP 1 LAST OFFPAGE TRUE
J 0
(-2675 5350);
DISPLAY 0.872340 (-2675 5350);
PAINT GREEN (-2675 5350);
DISPLAY INVISIBLE (-2675 5350);
FORCEPROP 1 LAST COMMENT_BODY TRUE
J 0
(-3045 5380);
DISPLAY 0.872340 (-3045 5380);
PAINT GREEN (-3045 5380);
DISPLAY INVISIBLE (-3045 5380);
FORCEPROP 2 LAST PATH I10
J 2
(-3050 5550);
DISPLAY 0.680851 (-3050 5550);
DISPLAY INVISIBLE (-3050 5550);
FORCEADD OFFPAGE..2
(-3000 5425);
FORCEPROP 2 LAST $XR0 180 
J 0
(-2811 5425);
DISPLAY 0.638298 (-2811 5425);
PAINT MONO (-2811 5425);
FORCEPROP 2 LAST CDS_LIB standard
J 0
(-3000 5425);
DISPLAY INVISIBLE (-3000 5425);
FORCEPROP 1 LAST OFFPAGE TRUE
J 0
(-2675 5300);
DISPLAY 0.872340 (-2675 5300);
PAINT GREEN (-2675 5300);
DISPLAY INVISIBLE (-2675 5300);
FORCEPROP 1 LAST COMMENT_BODY TRUE
J 0
(-3045 5330);
DISPLAY 0.872340 (-3045 5330);
PAINT GREEN (-3045 5330);
DISPLAY INVISIBLE (-3045 5330);
FORCEPROP 2 LAST PATH I11
J 0
(-2825 5500);
DISPLAY 0.680851 (-2825 5500);
DISPLAY INVISIBLE (-2825 5500);
FORCEADD OFFPAGE..1
R 2
(-3025 5625);
FORCEPROP 2 LAST $XR0 180 
J 0
(-2839 5625);
DISPLAY 0.638298 (-2839 5625);
PAINT MONO (-2839 5625);
FORCEPROP 2 LAST CDS_LIB standard
J 2
(-3025 5625);
DISPLAY INVISIBLE (-3025 5625);
FORCEPROP 1 LAST OFFPAGE TRUE
J 2
(-3350 5500);
DISPLAY 0.872340 (-3350 5500);
PAINT GREEN (-3350 5500);
DISPLAY INVISIBLE (-3350 5500);
FORCEPROP 1 LAST COMMENT_BODY TRUE
J 2
(-3150 5525);
DISPLAY 0.872340 (-3150 5525);
PAINT GREEN (-3150 5525);
DISPLAY INVISIBLE (-3150 5525);
FORCEPROP 2 LAST PATH I12
J 2
(-3075 5700);
DISPLAY 0.680851 (-3075 5700);
DISPLAY INVISIBLE (-3075 5700);
FORCEADD OFFPAGE..1
R 2
(-3025 5575);
FORCEPROP 2 LAST $XR0 180 
J 0
(-2839 5575);
DISPLAY 0.638298 (-2839 5575);
PAINT MONO (-2839 5575);
FORCEPROP 2 LAST CDS_LIB standard
J 0
(-3025 5575);
DISPLAY INVISIBLE (-3025 5575);
FORCEPROP 1 LAST OFFPAGE TRUE
J 2
(-3350 5450);
DISPLAY 0.872340 (-3350 5450);
PAINT GREEN (-3350 5450);
DISPLAY INVISIBLE (-3350 5450);
FORCEPROP 1 LAST COMMENT_BODY TRUE
J 2
(-3150 5475);
DISPLAY 0.872340 (-3150 5475);
PAINT GREEN (-3150 5475);
DISPLAY INVISIBLE (-3150 5475);
FORCEPROP 2 LAST PATH I13
J 0
(-2850 5650);
DISPLAY 0.680851 (-2850 5650);
DISPLAY INVISIBLE (-2850 5650);
FORCEADD Q_XTAL_4P_13BI_24GND..1
R 2
(-7000 1675);
FORCEPROP 1 LAST LOCATION Y9
J 2
(-6867 2041);
DISPLAY 0.723404 (-6867 2041);
PAINT GREEN (-6867 2041);
FORCEPROP 2 LAST SEC 1
J 0
(-6875 2175);
DISPLAY 0.680851 (-6875 2175);
PAINT MONO (-6875 2175);
DISPLAY INVISIBLE (-6875 2175);
FORCEPROP 2 LASTPIN (-6725 1550) $PN 2
J 0
(-6715 1560);
DISPLAY 0.680851 (-6715 1560);
PAINT MONO (-6715 1560);
FORCEPROP 2 LASTPIN (-7275 1550) $PN 4
J 2
(-7285 1560);
DISPLAY 0.680851 (-7285 1560);
PAINT MONO (-7285 1560);
FORCEPROP 2 LASTPIN (-6725 1750) $PN 1
J 0
(-6715 1760);
DISPLAY 0.680851 (-6715 1760);
PAINT MONO (-6715 1760);
FORCEPROP 2 LASTPIN (-7275 1750) $PN 3
J 2
(-7285 1760);
DISPLAY 0.680851 (-7285 1760);
PAINT MONO (-7285 1760);
FORCEPROP 2 LAST PART_TYPE SMLF
J 2
(-6875 2125);
DISPLAY 0.680851 (-6875 2125);
FORCEPROP 2 LAST ROOM USB3_HUB1_CYP
J 0
(-7250 2175);
DISPLAY 0.680851 (-7250 2175);
PAINT RED (-7250 2175);
FORCEPROP 2 LAST VALUE 26MHZ
J 2
(-6875 2075);
DISPLAY 0.680851 (-6875 2075);
FORCEPROP 1 LAST MATERIAL MISC
J 2
(-6867 1854);
DISPLAY 0.723404 (-6867 1854);
PAINT GREEN (-6867 1854);
FORCEPROP 2 LAST SEC_TYPE 
J 0
(-6875 2175);
DISPLAY 0.680851 (-6875 2175);
DISPLAY INVISIBLE (-6875 2175);
FORCEPROP 1 LAST CDS_LMAN_SYM_OUTLINE -125,175,125,-175
J 2
(-7000 1675);
DISPLAY 0.468085 (-7000 1675);
PAINT GREEN (-7000 1675);
DISPLAY INVISIBLE (-7000 1675);
FORCEPROP 1 LAST PIN_NAMES_ROTATE True
J 2
(-7000 1675);
DISPLAY 0.489362 (-7000 1675);
PAINT GREEN (-7000 1675);
DISPLAY INVISIBLE (-7000 1675);
FORCEPROP 2 LAST CDS_LIB pure_quanta
J 2
(-7000 1675);
DISPLAY INVISIBLE (-7000 1675);
FORCEPROP 1 LAST PATH I14
J 2
(-7125 1500);
DISPLAY 0.723404 (-7125 1500);
PAINT GREEN (-7125 1500);
DISPLAY INVISIBLE (-7125 1500);
FORCEPROP 1 LAST PART_NUMBER BG626000049
J 2
(-6867 1950);
DISPLAY 0.723404 (-6867 1950);
PAINT GREEN (-6867 1950);
DISPLAY INVISIBLE (-6867 1950);
FORCEADD GND..1
(-8000 1025);
FORCEPROP 3 LASTPIN (-8000 1075) SIG_NAME GND\g
J 0
(-7990 1085);
DISPLAY 0.659574 (-7990 1085);
PAINT MONO (-7990 1085);
DISPLAY INVISIBLE (-7990 1085);
FORCEPROP 2 LAST CDS_LIB pure_quanta_power
J 0
(-8000 1025);
DISPLAY INVISIBLE (-8000 1025);
FORCEPROP 1 LAST SIZE 1B
J 0
(-7925 975);
DISPLAY 0.872340 (-7925 975);
PAINT GREEN (-7925 975);
DISPLAY INVISIBLE (-7925 975);
FORCEPROP 1 LAST HDL_POWER GND
J 0
(-8000 1175);
DISPLAY 0.872340 (-8000 1175);
PAINT GREEN (-8000 1175);
DISPLAY INVISIBLE (-8000 1175);
FORCEPROP 1 LAST PATH I15
J 0
(-7925 1025);
DISPLAY 0.872340 (-7925 1025);
PAINT AQUA (-7925 1025);
DISPLAY INVISIBLE (-7925 1025);
FORCEADD GND..1
(-6350 1000);
FORCEPROP 3 LASTPIN (-6350 1050) SIG_NAME GND\g
J 0
(-6340 1060);
DISPLAY 0.659574 (-6340 1060);
PAINT MONO (-6340 1060);
DISPLAY INVISIBLE (-6340 1060);
FORCEPROP 2 LAST CDS_LIB pure_quanta_power
J 0
(-6350 1000);
DISPLAY INVISIBLE (-6350 1000);
FORCEPROP 1 LAST SIZE 1B
J 0
(-6275 950);
DISPLAY 0.872340 (-6275 950);
PAINT GREEN (-6275 950);
DISPLAY INVISIBLE (-6275 950);
FORCEPROP 1 LAST HDL_POWER GND
J 0
(-6350 1150);
DISPLAY 0.872340 (-6350 1150);
PAINT GREEN (-6350 1150);
DISPLAY INVISIBLE (-6350 1150);
FORCEPROP 1 LAST PATH I16
J 0
(-6275 1000);
DISPLAY 0.872340 (-6275 1000);
PAINT AQUA (-6275 1000);
DISPLAY INVISIBLE (-6275 1000);
FORCEADD OFFPAGE..1
(-8575 600);
FORCEPROP 2 LAST $XR2 235 
J 0
(-9067 600);
DISPLAY 0.638298 (-9067 600);
PAINT MONO (-9067 600);
FORCEPROP 2 LAST $XR1 178 
J 0
(-8947 600);
DISPLAY 0.638298 (-8947 600);
PAINT MONO (-8947 600);
FORCEPROP 2 LAST $XR0 246 
J 0
(-8827 600);
DISPLAY 0.638298 (-8827 600);
PAINT MONO (-8827 600);
FORCEPROP 2 LAST CDS_LIB standard
J 0
(-8575 600);
DISPLAY INVISIBLE (-8575 600);
FORCEPROP 1 LAST OFFPAGE TRUE
J 0
(-8250 475);
DISPLAY 0.872340 (-8250 475);
PAINT GREEN (-8250 475);
DISPLAY INVISIBLE (-8250 475);
FORCEPROP 1 LAST COMMENT_BODY TRUE
J 0
(-8450 500);
DISPLAY 0.872340 (-8450 500);
PAINT GREEN (-8450 500);
DISPLAY INVISIBLE (-8450 500);
FORCEPROP 2 LAST PATH I19
J 0
(-8525 675);
DISPLAY 0.680851 (-8525 675);
DISPLAY INVISIBLE (-8525 675);
FORCEADD OFFPAGE..3
R 2
(-6275 5775);
FORCEPROP 2 LAST $XR0 180 
J 0
(-6555 5775);
DISPLAY 0.638298 (-6555 5775);
PAINT MONO (-6555 5775);
FORCEPROP 2 LAST CDS_LIB standard
J 2
(-6275 5775);
DISPLAY INVISIBLE (-6275 5775);
FORCEPROP 1 LAST OFFPAGE TRUE
J 2
(-6600 5650);
DISPLAY 0.872340 (-6600 5650);
PAINT GREEN (-6600 5650);
DISPLAY INVISIBLE (-6600 5650);
FORCEPROP 1 LAST COMMENT_BODY TRUE
J 2
(-6225 5675);
DISPLAY 0.872340 (-6225 5675);
PAINT GREEN (-6225 5675);
DISPLAY INVISIBLE (-6225 5675);
FORCEPROP 2 LAST PATH I2
J 2
(-6475 5850);
DISPLAY 0.680851 (-6475 5850);
DISPLAY INVISIBLE (-6475 5850);
FORCEADD Q_RES..1
(-7450 600);
FORCEPROP 1 LAST LOCATION R4451
J 0
(-7725 600);
DISPLAY 0.787234 (-7725 600);
FORCEPROP 0 LAST $SEC 1
J 0
(-7650 700);
DISPLAY 0.680851 (-7650 700);
PAINT MONO (-7650 700);
DISPLAY INVISIBLE (-7650 700);
FORCEPROP 0 LAST CDS_SEC 1
J 0
(-7650 700);
DISPLAY 0.680851 (-7650 700);
DISPLAY INVISIBLE (-7650 700);
FORCEPROP 1 LASTPIN (-7550 600) $PN 1
J 0
(-7538 612);
DISPLAY 0.787234 (-7538 612);
PAINT MONO (-7538 612);
FORCEPROP 1 LASTPIN (-7350 600) $PN 2
J 0
(-7388 612);
DISPLAY 0.787234 (-7388 612);
PAINT MONO (-7388 612);
FORCEPROP 1 LAST VALUE 33.2
J 2
(-7150 600);
DISPLAY 0.787234 (-7150 600);
FORCEPROP 1 LAST WATTAGE 1/16W
J 2
(-7550 550);
DISPLAY 0.787234 (-7550 550);
FORCEPROP 1 LAST MATERIAL CHIP
J 0
(-7350 550);
DISPLAY 0.787234 (-7350 550);
FORCEPROP 1 LAST TOLERANCE 1%
J 0
(-7500 550);
DISPLAY 0.787234 (-7500 550);
FORCEPROP 2 LAST ROOM USB3_HUB1_CYP
J 0
(-7650 700);
DISPLAY 0.680851 (-7650 700);
PAINT RED (-7650 700);
FORCEPROP 1 LAST PACK_TYPE 0402LF
J 0
(-7150 550);
DISPLAY 0.787234 (-7150 550);
FORCEPROP 2 LAST CDS_LIB pure_quanta
J 0
(-7450 600);
DISPLAY INVISIBLE (-7450 600);
FORCEPROP 1 LAST PATH I20
J 0
(-7500 750);
DISPLAY 0.978723 (-7500 750);
PAINT WHITE (-7500 750);
DISPLAY INVISIBLE (-7500 750);
FORCEPROP 1 LAST PART_NUMBER CS03322FB03
J 0
(-7650 650);
DISPLAY 0.787234 (-7650 650);
DISPLAY INVISIBLE (-7650 650);
FORCEADD UNIVERSAL_POWER..1
(-6875 1150);
FORCEPROP 3 LASTPIN (-6875 1100) SIG_NAME P3V3_AUX\g
J 0
(-6865 1110);
DISPLAY 0.659574 (-6865 1110);
PAINT MONO (-6865 1110);
DISPLAY INVISIBLE (-6865 1110);
FORCEPROP 1 LAST HDL_POWER P3V3_AUX
J 1
(-6875 1200);
DISPLAY 0.489362 (-6875 1200);
PAINT GREEN (-6875 1200);
FORCEPROP 2 LAST CDS_LIB pure_quanta_power
J 0
(-6875 1150);
DISPLAY INVISIBLE (-6875 1150);
FORCEPROP 2 LAST BOM_COST VR_SYSTEM
J 0
(-6875 1250);
DISPLAY 0.617021 (-6875 1250);
PAINT PURPLE (-6875 1250);
DISPLAY INVISIBLE (-6875 1250);
FORCEPROP 1 LAST PATH I22
J 0
(-6825 1175);
DISPLAY 0.872340 (-6825 1175);
PAINT AQUA (-6825 1175);
DISPLAY INVISIBLE (-6825 1175);
FORCEADD Q_RES..2
(-5875 375);
FORCEPROP 1 LAST LOCATION R4453
J 0
(-5830 500);
DISPLAY 0.978723 (-5830 500);
FORCEPROP 0 LAST $SEC 1
J 0
(-5825 550);
DISPLAY 0.680851 (-5825 550);
PAINT MONO (-5825 550);
DISPLAY INVISIBLE (-5825 550);
FORCEPROP 0 LAST CDS_SEC 1
J 0
(-5825 550);
DISPLAY 0.680851 (-5825 550);
DISPLAY INVISIBLE (-5825 550);
FORCEPROP 1 LASTPIN (-5875 475) $PN 1
J 0
(-5870 437);
DISPLAY 0.787234 (-5870 437);
PAINT MONO (-5870 437);
FORCEPROP 1 LASTPIN (-5875 275) $PN 2
J 0
(-5870 285);
DISPLAY 0.787234 (-5870 285);
PAINT MONO (-5870 285);
FORCEPROP 1 LAST VALUE 47K
J 0
(-5830 450);
DISPLAY 0.978723 (-5830 450);
FORCEPROP 1 LAST TOLERANCE 0.1%
J 0
(-5830 400);
DISPLAY 0.978723 (-5830 400);
FORCEPROP 1 LAST WATTAGE 1/16W
J 0
(-5835 350);
DISPLAY 0.978723 (-5835 350);
FORCEPROP 1 LAST MATERIAL EMPTY
J 0
(-5835 300);
DISPLAY 0.978723 (-5835 300);
FORCEPROP 1 LAST PACK_TYPE 0402LF
J 0
(-5835 200);
DISPLAY 0.978723 (-5835 200);
FORCEPROP 2 LAST ROOM USB3_HUB1_CYP
J 0
(-5825 550);
DISPLAY 0.553191 (-5825 550);
PAINT RED (-5825 550);
FORCEPROP 2 LAST CDS_LIB pure_quanta
J 0
(-5875 375);
DISPLAY INVISIBLE (-5875 375);
FORCEPROP 1 LAST PATH I23
J 0
(-5825 550);
DISPLAY 0.978723 (-5825 550);
PAINT WHITE (-5825 550);
DISPLAY INVISIBLE (-5825 550);
FORCEPROP 1 LAST PART_NUMBER CS34702BB05
J 0
(-5835 250);
DISPLAY 0.978723 (-5835 250);
DISPLAY INVISIBLE (-5835 250);
FORCEADD GND..1
(-5875 100);
FORCEPROP 3 LASTPIN (-5875 150) SIG_NAME GND\g
J 0
(-5865 160);
DISPLAY 0.659574 (-5865 160);
PAINT MONO (-5865 160);
DISPLAY INVISIBLE (-5865 160);
FORCEPROP 2 LAST CDS_LIB pure_quanta_power
J 0
(-5875 100);
DISPLAY INVISIBLE (-5875 100);
FORCEPROP 1 LAST SIZE 1B
J 0
(-5800 50);
DISPLAY 0.872340 (-5800 50);
PAINT GREEN (-5800 50);
DISPLAY INVISIBLE (-5800 50);
FORCEPROP 1 LAST HDL_POWER GND
J 0
(-5875 250);
DISPLAY 0.872340 (-5875 250);
PAINT GREEN (-5875 250);
DISPLAY INVISIBLE (-5875 250);
FORCEPROP 1 LAST PATH I24
J 0
(-5800 100);
DISPLAY 0.872340 (-5800 100);
PAINT AQUA (-5800 100);
DISPLAY INVISIBLE (-5800 100);
FORCEADD Q_CAP..1
(-6350 425);
FORCEPROP 1 LAST LOCATION C2317
J 0
(-6300 525);
DISPLAY 0.638298 (-6300 525);
FORCEPROP 0 LAST $SEC 1
J 0
(-6300 575);
DISPLAY 0.680851 (-6300 575);
PAINT MONO (-6300 575);
DISPLAY INVISIBLE (-6300 575);
FORCEPROP 0 LAST CDS_SEC 1
J 0
(-6300 575);
DISPLAY 0.680851 (-6300 575);
DISPLAY INVISIBLE (-6300 575);
FORCEPROP 1 LASTPIN (-6350 525) $PN 1
J 0
(-6340 505);
DISPLAY 0.787234 (-6340 505);
PAINT MONO (-6340 505);
FORCEPROP 1 LASTPIN (-6350 325) $PN 2
J 0
(-6340 305);
DISPLAY 0.787234 (-6340 305);
PAINT MONO (-6340 305);
FORCEPROP 1 LAST TOLERANCE 10%
J 0
(-6300 375);
DISPLAY 0.638298 (-6300 375);
FORCEPROP 1 LAST VALUE 1UF
J 0
(-6300 475);
DISPLAY 0.638298 (-6300 475);
FORCEPROP 1 LAST PACK_TYPE C0402
J 0
(-6300 225);
DISPLAY 0.638298 (-6300 225);
FORCEPROP 1 LAST MATERIAL X6S
J 0
(-6300 325);
DISPLAY 0.638298 (-6300 325);
FORCEPROP 1 LAST VOLTAGE 25V
J 0
(-6300 425);
DISPLAY 0.638298 (-6300 425);
FORCEPROP 2 LAST ROOM USB3_HUB1_CYP
J 0
(-6300 575);
DISPLAY 0.446809 (-6300 575);
PAINT RED (-6300 575);
FORCEPROP 2 LAST CDS_LIB pure_quanta
J 0
(-6350 425);
DISPLAY INVISIBLE (-6350 425);
FORCEPROP 1 LAST PATH I25
J 0
(-6300 575);
DISPLAY 0.978723 (-6300 575);
PAINT WHITE (-6300 575);
DISPLAY INVISIBLE (-6300 575);
FORCEPROP 1 LAST PART_NUMBER CH5104KEB02
J 0
(-6300 275);
DISPLAY 0.638298 (-6300 275);
DISPLAY INVISIBLE (-6300 275);
FORCEADD P1V0_AUX..1
(-2475 6425);
FORCEPROP 3 LASTPIN (-2475 6375) SIG_NAME P5V_AUX\g
J 0
(-2465 6385);
DISPLAY 0.659574 (-2465 6385);
PAINT MONO (-2465 6385);
DISPLAY INVISIBLE (-2465 6385);
FORCEPROP 1 LAST HDL_POWER P5V_AUX
J 1
(-2465 6465);
DISPLAY 0.617021 (-2465 6465);
PAINT GREEN (-2465 6465);
FORCEPROP 2 LAST BOM_COST VR_SYSTEM 
J 0
(-2449 6501);
DISPLAY 0.680851 (-2449 6501);
DISPLAY INVISIBLE (-2449 6501);
FORCEPROP 2 LAST CDS_LIB pure_quanta_power
J 0
(-2475 6425);
DISPLAY INVISIBLE (-2475 6425);
FORCEPROP 1 LAST PATH I26
J 0
(-2425 6450);
DISPLAY 0.872340 (-2425 6450);
PAINT AQUA (-2425 6450);
DISPLAY INVISIBLE (-2425 6450);
FORCEADD Q_RES..1
(-2825 6125);
FORCEPROP 1 LAST LOCATION R4450
J 0
(-3050 6125);
DISPLAY 0.638298 (-3050 6125);
FORCEPROP 0 LAST $SEC 1
J 0
(-3075 6250);
DISPLAY 0.680851 (-3075 6250);
PAINT MONO (-3075 6250);
DISPLAY INVISIBLE (-3075 6250);
FORCEPROP 0 LAST CDS_SEC 1
J 0
(-3075 6250);
DISPLAY 0.680851 (-3075 6250);
DISPLAY INVISIBLE (-3075 6250);
FORCEPROP 1 LASTPIN (-2925 6125) $PN 1
J 0
(-2913 6137);
DISPLAY 0.787234 (-2913 6137);
PAINT MONO (-2913 6137);
FORCEPROP 1 LASTPIN (-2725 6125) $PN 2
J 0
(-2763 6137);
DISPLAY 0.787234 (-2763 6137);
PAINT MONO (-2763 6137);
FORCEPROP 1 LAST TOLERANCE 5%
J 0
(-3025 6075);
DISPLAY 0.723404 (-3025 6075);
PAINT SKYBLUE (-3025 6075);
FORCEPROP 1 LAST PACK_TYPE 0402LF
J 0
(-2925 6200);
DISPLAY 0.723404 (-2925 6200);
FORCEPROP 1 LAST MATERIAL CHIP
J 0
(-2900 6075);
DISPLAY 0.723404 (-2900 6075);
FORCEPROP 1 LAST WATTAGE 1/16W
J 2
(-2525 6075);
DISPLAY 0.723404 (-2525 6075);
PAINT SKYBLUE (-2525 6075);
FORCEPROP 1 LAST VALUE 0
J 2
(-2675 6125);
DISPLAY 0.723404 (-2675 6125);
FORCEPROP 2 LAST ROOM USB3_HUB1_CYP
J 0
(-3075 6300);
DISPLAY 0.680851 (-3075 6300);
PAINT RED (-3075 6300);
FORCEPROP 2 LAST CDS_LIB pure_quanta
J 0
(-2825 6125);
DISPLAY INVISIBLE (-2825 6125);
FORCEPROP 1 LAST PATH I27
J 0
(-2875 6275);
DISPLAY 0.978723 (-2875 6275);
PAINT WHITE (-2875 6275);
DISPLAY INVISIBLE (-2875 6275);
FORCEPROP 1 LAST PART_NUMBER CS00002JB13
J 0
(-3075 6250);
DISPLAY 0.723404 (-3075 6250);
PAINT WHITE (-3075 6250);
DISPLAY INVISIBLE (-3075 6250);
FORCEADD Q_CAP..1
(-1525 6025);
FORCEPROP 1 LAST LOCATION C6027
J 0
(-1475 6125);
DISPLAY 0.638298 (-1475 6125);
FORCEPROP 0 LAST $SEC 1
J 0
(-1475 6175);
DISPLAY 0.680851 (-1475 6175);
PAINT MONO (-1475 6175);
DISPLAY INVISIBLE (-1475 6175);
FORCEPROP 0 LAST CDS_SEC 1
J 0
(-1475 6175);
DISPLAY 0.680851 (-1475 6175);
DISPLAY INVISIBLE (-1475 6175);
FORCEPROP 1 LASTPIN (-1525 6125) $PN 1
J 0
(-1515 6105);
DISPLAY 0.787234 (-1515 6105);
PAINT MONO (-1515 6105);
FORCEPROP 1 LASTPIN (-1525 5925) $PN 2
J 0
(-1515 5905);
DISPLAY 0.787234 (-1515 5905);
PAINT MONO (-1515 5905);
FORCEPROP 2 LAST ROOM USB3_HUB1_CYP
J 0
(-1475 6175);
DISPLAY 0.553191 (-1475 6175);
PAINT RED (-1475 6175);
FORCEPROP 1 LAST VALUE 22UF
J 0
(-1475 6075);
DISPLAY 0.638298 (-1475 6075);
FORCEPROP 1 LAST VOLTAGE 16V
J 0
(-1475 6025);
DISPLAY 0.638298 (-1475 6025);
FORCEPROP 1 LAST TOLERANCE 20%
J 0
(-1475 5975);
DISPLAY 0.638298 (-1475 5975);
FORCEPROP 1 LAST MATERIAL X6S
J 0
(-1475 5925);
DISPLAY 0.638298 (-1475 5925);
FORCEPROP 1 LAST PACK_TYPE C0805
J 0
(-1475 5825);
DISPLAY 0.638298 (-1475 5825);
FORCEPROP 2 LAST CDS_LIB pure_quanta
J 0
(-1525 6025);
DISPLAY INVISIBLE (-1525 6025);
FORCEPROP 1 LAST PATH I28
J 0
(-1475 6175);
DISPLAY 0.978723 (-1475 6175);
PAINT WHITE (-1475 6175);
DISPLAY INVISIBLE (-1475 6175);
FORCEPROP 1 LAST PART_NUMBER CH6223MEA00
J 0
(-1475 5875);
DISPLAY 0.638298 (-1475 5875);
DISPLAY INVISIBLE (-1475 5875);
FORCEADD Q_CAP..1
(-1075 6000);
FORCEPROP 1 LAST LOCATION C6028
J 0
(-1025 6100);
DISPLAY 0.638298 (-1025 6100);
FORCEPROP 0 LAST $SEC 1
J 0
(-1025 6150);
DISPLAY 0.680851 (-1025 6150);
PAINT MONO (-1025 6150);
DISPLAY INVISIBLE (-1025 6150);
FORCEPROP 0 LAST CDS_SEC 1
J 0
(-1025 6150);
DISPLAY 0.680851 (-1025 6150);
DISPLAY INVISIBLE (-1025 6150);
FORCEPROP 1 LASTPIN (-1075 6100) $PN 1
J 0
(-1065 6080);
DISPLAY 0.787234 (-1065 6080);
PAINT MONO (-1065 6080);
FORCEPROP 1 LASTPIN (-1075 5900) $PN 2
J 0
(-1065 5880);
DISPLAY 0.787234 (-1065 5880);
PAINT MONO (-1065 5880);
FORCEPROP 2 LAST ROOM USB3_HUB1_CYP
J 0
(-1025 6150);
DISPLAY 0.680851 (-1025 6150);
PAINT RED (-1025 6150);
FORCEPROP 1 LAST VALUE 470PF
J 0
(-1025 6050);
DISPLAY 0.638298 (-1025 6050);
FORCEPROP 1 LAST VOLTAGE 50V
J 0
(-1025 6000);
DISPLAY 0.638298 (-1025 6000);
FORCEPROP 1 LAST MATERIAL X7R
J 0
(-1025 5900);
DISPLAY 0.638298 (-1025 5900);
FORCEPROP 1 LAST TOLERANCE 10%
J 0
(-1025 5950);
DISPLAY 0.638298 (-1025 5950);
FORCEPROP 1 LAST PACK_TYPE 0402
J 0
(-1025 5800);
DISPLAY 0.638298 (-1025 5800);
FORCEPROP 2 LAST CDS_LIB pure_quanta
J 0
(-1075 6000);
DISPLAY INVISIBLE (-1075 6000);
FORCEPROP 1 LAST PATH I29
J 0
(-1025 6150);
DISPLAY 0.978723 (-1025 6150);
PAINT WHITE (-1025 6150);
DISPLAY INVISIBLE (-1025 6150);
FORCEPROP 1 LAST PART_NUMBER TMP_QCH14706KB18
J 0
(-1025 5850);
DISPLAY 0.638298 (-1025 5850);
DISPLAY INVISIBLE (-1025 5850);
FORCEADD OFFPAGE..3
R 2
(-6275 5725);
FORCEPROP 2 LAST $XR0 180 
J 0
(-6555 5725);
DISPLAY 0.638298 (-6555 5725);
PAINT MONO (-6555 5725);
FORCEPROP 2 LAST CDS_LIB standard
J 0
(-6275 5725);
DISPLAY INVISIBLE (-6275 5725);
FORCEPROP 1 LAST OFFPAGE TRUE
J 2
(-6600 5600);
DISPLAY 0.872340 (-6600 5600);
PAINT GREEN (-6600 5600);
DISPLAY INVISIBLE (-6600 5600);
FORCEPROP 1 LAST COMMENT_BODY TRUE
J 2
(-6225 5625);
DISPLAY 0.872340 (-6225 5625);
PAINT GREEN (-6225 5625);
DISPLAY INVISIBLE (-6225 5625);
FORCEPROP 2 LAST PATH I3
J 0
(-6225 5800);
DISPLAY 0.680851 (-6225 5800);
DISPLAY INVISIBLE (-6225 5800);
FORCEADD GND..1
(-975 5400);
FORCEPROP 3 LASTPIN (-975 5450) SIG_NAME GND\g
J 0
(-965 5460);
DISPLAY 0.659574 (-965 5460);
PAINT MONO (-965 5460);
DISPLAY INVISIBLE (-965 5460);
FORCEPROP 2 LAST CDS_LIB pure_quanta_power
J 0
(-975 5400);
DISPLAY INVISIBLE (-975 5400);
FORCEPROP 1 LAST SIZE 1B
J 0
(-900 5350);
DISPLAY 0.872340 (-900 5350);
PAINT GREEN (-900 5350);
DISPLAY INVISIBLE (-900 5350);
FORCEPROP 1 LAST HDL_POWER GND
J 0
(-975 5550);
DISPLAY 0.872340 (-975 5550);
PAINT GREEN (-975 5550);
DISPLAY INVISIBLE (-975 5550);
FORCEPROP 1 LAST PATH I30
J 0
(-900 5400);
DISPLAY 0.872340 (-900 5400);
PAINT AQUA (-900 5400);
DISPLAY INVISIBLE (-900 5400);
FORCEADD P1V0_AUX..1
(-1525 6400);
FORCEPROP 3 LASTPIN (-1525 6350) SIG_NAME P5V_AUX\g
J 0
(-1515 6360);
DISPLAY 0.659574 (-1515 6360);
PAINT MONO (-1515 6360);
DISPLAY INVISIBLE (-1515 6360);
FORCEPROP 1 LAST HDL_POWER P5V_AUX
J 1
(-1515 6440);
DISPLAY 0.617021 (-1515 6440);
PAINT GREEN (-1515 6440);
FORCEPROP 2 LAST CDS_LIB pure_quanta_power
J 0
(-1525 6400);
DISPLAY INVISIBLE (-1525 6400);
FORCEPROP 2 LAST BOM_COST VR_SYSTEM 
J 0
(-1499 6476);
DISPLAY 0.680851 (-1499 6476);
DISPLAY INVISIBLE (-1499 6476);
FORCEPROP 1 LAST PATH I31
J 0
(-1475 6425);
DISPLAY 0.872340 (-1475 6425);
PAINT AQUA (-1475 6425);
DISPLAY INVISIBLE (-1475 6425);
FORCEADD GND..1
(-3800 1075);
FORCEPROP 3 LASTPIN (-3800 1125) SIG_NAME GND\g
J 0
(-3790 1135);
DISPLAY 0.659574 (-3790 1135);
PAINT MONO (-3790 1135);
DISPLAY INVISIBLE (-3790 1135);
FORCEPROP 1 LAST SIZE 1B
J 0
(-3725 1025);
DISPLAY 0.872340 (-3725 1025);
PAINT GREEN (-3725 1025);
DISPLAY INVISIBLE (-3725 1025);
FORCEPROP 2 LAST CDS_LIB pure_quanta_power
J 0
(-3800 1075);
DISPLAY INVISIBLE (-3800 1075);
FORCEPROP 1 LAST HDL_POWER GND
J 0
(-3800 1225);
DISPLAY 0.872340 (-3800 1225);
PAINT GREEN (-3800 1225);
DISPLAY INVISIBLE (-3800 1225);
FORCEPROP 1 LAST PATH I36
J 0
(-3725 1075);
DISPLAY 0.872340 (-3725 1075);
PAINT AQUA (-3725 1075);
DISPLAY INVISIBLE (-3725 1075);
FORCEADD Q_RES..1
(-7000 4225);
FORCEPROP 1 LAST LOCATION R6202
J 0
(-7275 4225);
DISPLAY 0.787234 (-7275 4225);
FORCEPROP 0 LAST $SEC 1
J 0
(-6925 4375);
DISPLAY 0.680851 (-6925 4375);
PAINT MONO (-6925 4375);
DISPLAY INVISIBLE (-6925 4375);
FORCEPROP 0 LAST CDS_SEC 1
J 0
(-6925 4375);
DISPLAY 0.680851 (-6925 4375);
DISPLAY INVISIBLE (-6925 4375);
FORCEPROP 1 LASTPIN (-7100 4225) $PN 1
J 0
(-7088 4237);
DISPLAY 0.787234 (-7088 4237);
PAINT MONO (-7088 4237);
FORCEPROP 1 LASTPIN (-6900 4225) $PN 2
J 0
(-6938 4237);
DISPLAY 0.787234 (-6938 4237);
PAINT MONO (-6938 4237);
FORCEPROP 1 LAST TOLERANCE 1%
J 0
(-6925 4325);
DISPLAY 0.787234 (-6925 4325);
FORCEPROP 1 LAST VALUE 200
J 2
(-6750 4225);
DISPLAY 0.787234 (-6750 4225);
FORCEPROP 1 LAST MATERIAL CHIP
J 0
(-7150 4325);
DISPLAY 0.787234 (-7150 4325);
FORCEPROP 2 LAST ROOM USB3_HUB1_CYP
J 0
(-6800 4325);
DISPLAY 0.680851 (-6800 4325);
PAINT RED (-6800 4325);
FORCEPROP 1 LAST WATTAGE 1/16W
J 2
(-6525 4275);
DISPLAY 0.787234 (-6525 4275);
FORCEPROP 1 LAST PACK_TYPE 0402LF
J 0
(-6700 4225);
DISPLAY 0.787234 (-6700 4225);
FORCEPROP 2 LAST CDS_LIB pure_quanta
J 0
(-7000 4225);
DISPLAY INVISIBLE (-7000 4225);
FORCEPROP 1 LAST PATH I37
J 0
(-7050 4375);
DISPLAY 0.978723 (-7050 4375);
PAINT WHITE (-7050 4375);
DISPLAY INVISIBLE (-7050 4375);
FORCEPROP 1 LAST PART_NUMBER CS12002FB06
J 0
(-7150 4275);
DISPLAY 0.787234 (-7150 4275);
DISPLAY INVISIBLE (-7150 4275);
FORCEADD Q_RES..1
(-7025 4125);
FORCEPROP 1 LAST LOCATION R6203
J 0
(-7300 4125);
DISPLAY 0.787234 (-7300 4125);
FORCEPROP 0 LAST $SEC 1
J 0
(-6625 4175);
DISPLAY 0.680851 (-6625 4175);
PAINT MONO (-6625 4175);
DISPLAY INVISIBLE (-6625 4175);
FORCEPROP 0 LAST CDS_SEC 1
J 0
(-6625 4175);
DISPLAY 0.680851 (-6625 4175);
DISPLAY INVISIBLE (-6625 4175);
FORCEPROP 1 LASTPIN (-7125 4125) $PN 1
J 0
(-7113 4137);
DISPLAY 0.787234 (-7113 4137);
PAINT MONO (-7113 4137);
FORCEPROP 1 LASTPIN (-6925 4125) $PN 2
J 0
(-6963 4137);
DISPLAY 0.787234 (-6963 4137);
PAINT MONO (-6963 4137);
FORCEPROP 1 LAST MATERIAL CHIP
J 0
(-7375 4050);
DISPLAY 0.787234 (-7375 4050);
FORCEPROP 1 LAST VALUE 6.04K
J 2
(-6700 4125);
DISPLAY 0.787234 (-6700 4125);
FORCEPROP 2 LAST ROOM USB3_HUB1_CYP
J 0
(-7200 4000);
DISPLAY 0.680851 (-7200 4000);
PAINT RED (-7200 4000);
FORCEPROP 1 LAST TOLERANCE 1%
J 0
(-6550 4050);
DISPLAY 0.787234 (-6550 4050);
FORCEPROP 1 LAST PACK_TYPE 0402LF
J 0
(-6625 4125);
DISPLAY 0.787234 (-6625 4125);
FORCEPROP 1 LAST WATTAGE 1/16W
J 2
(-6575 4050);
DISPLAY 0.787234 (-6575 4050);
FORCEPROP 2 LAST CDS_LIB pure_quanta
J 0
(-7025 4125);
DISPLAY INVISIBLE (-7025 4125);
FORCEPROP 1 LAST PATH I39
J 0
(-7075 4275);
DISPLAY 0.978723 (-7075 4275);
PAINT WHITE (-7075 4275);
DISPLAY INVISIBLE (-7075 4275);
FORCEPROP 1 LAST PART_NUMBER CS26042FB04
J 0
(-7200 4050);
DISPLAY 0.787234 (-7200 4050);
DISPLAY INVISIBLE (-7200 4050);
FORCEADD OFFPAGE..1
(-6300 5475);
FORCEPROP 2 LAST $XR0 180 
J 0
(-6552 5475);
DISPLAY 0.638298 (-6552 5475);
PAINT MONO (-6552 5475);
FORCEPROP 2 LAST CDS_LIB standard
J 0
(-6300 5475);
DISPLAY INVISIBLE (-6300 5475);
FORCEPROP 1 LAST OFFPAGE TRUE
J 0
(-5975 5350);
DISPLAY 0.872340 (-5975 5350);
PAINT GREEN (-5975 5350);
DISPLAY INVISIBLE (-5975 5350);
FORCEPROP 1 LAST COMMENT_BODY TRUE
J 0
(-6175 5375);
DISPLAY 0.872340 (-6175 5375);
PAINT GREEN (-6175 5375);
DISPLAY INVISIBLE (-6175 5375);
FORCEPROP 2 LAST PATH I4
J 0
(-6250 5550);
DISPLAY 0.680851 (-6250 5550);
DISPLAY INVISIBLE (-6250 5550);
FORCEADD GND..1
(-7725 4000);
FORCEPROP 3 LASTPIN (-7725 4050) SIG_NAME GND\g
J 0
(-7715 4060);
DISPLAY 0.659574 (-7715 4060);
PAINT MONO (-7715 4060);
DISPLAY INVISIBLE (-7715 4060);
FORCEPROP 1 LAST SIZE 1B
J 0
(-7650 3950);
DISPLAY 0.872340 (-7650 3950);
PAINT GREEN (-7650 3950);
DISPLAY INVISIBLE (-7650 3950);
FORCEPROP 2 LAST CDS_LIB pure_quanta_power
J 0
(-7725 4000);
DISPLAY INVISIBLE (-7725 4000);
FORCEPROP 1 LAST HDL_POWER GND
J 0
(-7725 4150);
DISPLAY 0.872340 (-7725 4150);
PAINT GREEN (-7725 4150);
DISPLAY INVISIBLE (-7725 4150);
FORCEPROP 1 LAST PATH I40
J 0
(-7650 4000);
DISPLAY 0.872340 (-7650 4000);
PAINT AQUA (-7650 4000);
DISPLAY INVISIBLE (-7650 4000);
FORCEADD Q_RES..2
(-7175 3275);
FORCEPROP 1 LAST LOCATION R6204
J 0
(-7130 3400);
DISPLAY 0.808511 (-7130 3400);
FORCEPROP 0 LAST $SEC 1
J 0
(-7125 3450);
DISPLAY 0.680851 (-7125 3450);
PAINT MONO (-7125 3450);
DISPLAY INVISIBLE (-7125 3450);
FORCEPROP 0 LAST CDS_SEC 1
J 0
(-7125 3450);
DISPLAY 0.680851 (-7125 3450);
DISPLAY INVISIBLE (-7125 3450);
FORCEPROP 1 LASTPIN (-7175 3375) $PN 1
J 0
(-7170 3337);
DISPLAY 0.787234 (-7170 3337);
PAINT MONO (-7170 3337);
FORCEPROP 1 LASTPIN (-7175 3175) $PN 2
J 0
(-7170 3185);
DISPLAY 0.787234 (-7170 3185);
PAINT MONO (-7170 3185);
FORCEPROP 2 LAST ROOM USB3_HUB1_CYP
J 0
(-7125 3450);
DISPLAY 0.553191 (-7125 3450);
PAINT RED (-7125 3450);
FORCEPROP 1 LAST WATTAGE 1/16W
J 0
(-7135 3250);
DISPLAY 0.638298 (-7135 3250);
FORCEPROP 1 LAST MATERIAL CHIP
J 0
(-7135 3200);
DISPLAY 0.638298 (-7135 3200);
FORCEPROP 1 LAST TOLERANCE 1%
J 0
(-7130 3300);
DISPLAY 0.638298 (-7130 3300);
FORCEPROP 1 LAST VALUE 10K
J 0
(-7130 3350);
DISPLAY 0.638298 (-7130 3350);
FORCEPROP 1 LAST PACK_TYPE 0402LF
J 0
(-7135 3100);
DISPLAY 0.638298 (-7135 3100);
FORCEPROP 2 LAST CDS_LIB pure_quanta
J 0
(-7175 3275);
DISPLAY INVISIBLE (-7175 3275);
FORCEPROP 1 LAST PATH I41
J 0
(-7125 3450);
DISPLAY 0.978723 (-7125 3450);
PAINT WHITE (-7125 3450);
DISPLAY INVISIBLE (-7125 3450);
FORCEPROP 1 LAST PART_NUMBER CS31002FB08
J 0
(-7135 3150);
DISPLAY 0.638298 (-7135 3150);
DISPLAY INVISIBLE (-7135 3150);
FORCEADD UNIVERSAL_POWER..1
(-7650 3775);
FORCEPROP 3 LASTPIN (-7650 3725) SIG_NAME P3V3_AUX\g
J 0
(-7640 3735);
DISPLAY 0.659574 (-7640 3735);
PAINT MONO (-7640 3735);
DISPLAY INVISIBLE (-7640 3735);
FORCEPROP 1 LAST HDL_POWER P3V3_AUX
J 1
(-7650 3825);
DISPLAY 0.489362 (-7650 3825);
PAINT GREEN (-7650 3825);
FORCEPROP 2 LAST CDS_LIB pure_quanta_power
J 0
(-7650 3775);
DISPLAY INVISIBLE (-7650 3775);
FORCEPROP 2 LAST BOM_COST VR_SYSTEM
J 0
(-7650 3875);
DISPLAY 0.617021 (-7650 3875);
PAINT PURPLE (-7650 3875);
DISPLAY INVISIBLE (-7650 3875);
FORCEPROP 1 LAST PATH I42
J 0
(-7600 3800);
DISPLAY 0.872340 (-7600 3800);
PAINT AQUA (-7600 3800);
DISPLAY INVISIBLE (-7600 3800);
FORCEADD Q_RES..2
(-7475 3275);
FORCEPROP 1 LAST LOCATION R6205
J 0
(-7430 3400);
DISPLAY 0.808511 (-7430 3400);
FORCEPROP 0 LAST $SEC 1
J 0
(-7425 3450);
DISPLAY 0.680851 (-7425 3450);
PAINT MONO (-7425 3450);
DISPLAY INVISIBLE (-7425 3450);
FORCEPROP 0 LAST CDS_SEC 1
J 0
(-7425 3450);
DISPLAY 0.680851 (-7425 3450);
DISPLAY INVISIBLE (-7425 3450);
FORCEPROP 1 LASTPIN (-7475 3375) $PN 1
J 0
(-7470 3337);
DISPLAY 0.787234 (-7470 3337);
PAINT MONO (-7470 3337);
FORCEPROP 1 LASTPIN (-7475 3175) $PN 2
J 0
(-7470 3185);
DISPLAY 0.787234 (-7470 3185);
PAINT MONO (-7470 3185);
FORCEPROP 1 LAST TOLERANCE 1%
J 0
(-7430 3300);
DISPLAY 0.638298 (-7430 3300);
FORCEPROP 1 LAST WATTAGE 1/16W
J 0
(-7435 3250);
DISPLAY 0.638298 (-7435 3250);
FORCEPROP 1 LAST MATERIAL CHIP
J 0
(-7435 3200);
DISPLAY 0.638298 (-7435 3200);
FORCEPROP 1 LAST PACK_TYPE 0402LF
J 0
(-7425 3150);
DISPLAY 0.638298 (-7425 3150);
FORCEPROP 2 LAST ROOM USB3_HUB1_CYP
J 0
(-7450 3450);
DISPLAY 0.446809 (-7450 3450);
PAINT RED (-7450 3450);
FORCEPROP 1 LAST VALUE 10K
J 0
(-7430 3350);
DISPLAY 0.638298 (-7430 3350);
FORCEPROP 2 LAST CDS_LIB pure_quanta
J 0
(-7475 3275);
DISPLAY INVISIBLE (-7475 3275);
FORCEPROP 1 LAST PATH I43
J 0
(-7425 3450);
DISPLAY 0.978723 (-7425 3450);
PAINT WHITE (-7425 3450);
DISPLAY INVISIBLE (-7425 3450);
FORCEPROP 1 LAST PART_NUMBER CS31002FB08
J 0
(-7435 3150);
DISPLAY 0.638298 (-7435 3150);
DISPLAY INVISIBLE (-7435 3150);
FORCEADD Q_RES..2
(-7775 3275);
FORCEPROP 1 LAST LOCATION R6206
J 0
(-7730 3400);
DISPLAY 0.808511 (-7730 3400);
FORCEPROP 0 LAST $SEC 1
J 0
(-7725 3450);
DISPLAY 0.680851 (-7725 3450);
PAINT MONO (-7725 3450);
DISPLAY INVISIBLE (-7725 3450);
FORCEPROP 0 LAST CDS_SEC 1
J 0
(-7725 3450);
DISPLAY 0.680851 (-7725 3450);
DISPLAY INVISIBLE (-7725 3450);
FORCEPROP 1 LASTPIN (-7775 3375) $PN 1
J 0
(-7770 3337);
DISPLAY 0.787234 (-7770 3337);
PAINT MONO (-7770 3337);
FORCEPROP 1 LASTPIN (-7775 3175) $PN 2
J 0
(-7770 3185);
DISPLAY 0.787234 (-7770 3185);
PAINT MONO (-7770 3185);
FORCEPROP 1 LAST PACK_TYPE 0402LF
J 0
(-7725 3150);
DISPLAY 0.638298 (-7725 3150);
FORCEPROP 1 LAST MATERIAL CHIP
J 0
(-7735 3200);
DISPLAY 0.638298 (-7735 3200);
FORCEPROP 1 LAST TOLERANCE 1%
J 0
(-7730 3300);
DISPLAY 0.638298 (-7730 3300);
FORCEPROP 1 LAST VALUE 10K
J 0
(-7730 3350);
DISPLAY 0.638298 (-7730 3350);
FORCEPROP 2 LAST ROOM USB3_HUB1_CYP
J 0
(-7750 3450);
DISPLAY 0.446809 (-7750 3450);
PAINT RED (-7750 3450);
FORCEPROP 1 LAST WATTAGE 1/16W
J 0
(-7735 3250);
DISPLAY 0.638298 (-7735 3250);
FORCEPROP 2 LAST CDS_LIB pure_quanta
J 0
(-7775 3275);
DISPLAY INVISIBLE (-7775 3275);
FORCEPROP 1 LAST PATH I44
J 0
(-7725 3450);
DISPLAY 0.978723 (-7725 3450);
PAINT WHITE (-7725 3450);
DISPLAY INVISIBLE (-7725 3450);
FORCEPROP 1 LAST PART_NUMBER CS31002FB08
J 0
(-7735 3150);
DISPLAY 0.638298 (-7735 3150);
DISPLAY INVISIBLE (-7735 3150);
FORCEADD Q_RES..2
(-8100 3275);
FORCEPROP 1 LAST LOCATION R6207
J 0
(-8055 3400);
DISPLAY 0.808511 (-8055 3400);
FORCEPROP 0 LAST $SEC 1
J 0
(-8050 3450);
DISPLAY 0.680851 (-8050 3450);
PAINT MONO (-8050 3450);
DISPLAY INVISIBLE (-8050 3450);
FORCEPROP 0 LAST CDS_SEC 1
J 0
(-8050 3450);
DISPLAY 0.680851 (-8050 3450);
DISPLAY INVISIBLE (-8050 3450);
FORCEPROP 1 LASTPIN (-8100 3375) $PN 1
J 0
(-8095 3337);
DISPLAY 0.787234 (-8095 3337);
PAINT MONO (-8095 3337);
FORCEPROP 1 LASTPIN (-8100 3175) $PN 2
J 0
(-8095 3185);
DISPLAY 0.787234 (-8095 3185);
PAINT MONO (-8095 3185);
FORCEPROP 1 LAST MATERIAL CHIP
J 0
(-8060 3200);
DISPLAY 0.638298 (-8060 3200);
FORCEPROP 1 LAST WATTAGE 1/16W
J 0
(-8060 3250);
DISPLAY 0.638298 (-8060 3250);
FORCEPROP 1 LAST TOLERANCE 1%
J 0
(-8055 3300);
DISPLAY 0.638298 (-8055 3300);
FORCEPROP 1 LAST VALUE 10K
J 0
(-8055 3350);
DISPLAY 0.638298 (-8055 3350);
FORCEPROP 1 LAST PACK_TYPE 0402LF
J 0
(-8050 3150);
DISPLAY 0.638298 (-8050 3150);
FORCEPROP 2 LAST ROOM USB3_HUB1_CYP
J 0
(-8075 3450);
DISPLAY 0.446809 (-8075 3450);
PAINT RED (-8075 3450);
FORCEPROP 2 LAST CDS_LIB pure_quanta
J 0
(-8100 3275);
DISPLAY INVISIBLE (-8100 3275);
FORCEPROP 1 LAST PATH I45
J 0
(-8050 3450);
DISPLAY 0.978723 (-8050 3450);
PAINT WHITE (-8050 3450);
DISPLAY INVISIBLE (-8050 3450);
FORCEPROP 1 LAST PART_NUMBER CS31002FB08
J 0
(-8060 3150);
DISPLAY 0.638298 (-8060 3150);
DISPLAY INVISIBLE (-8060 3150);
FORCEADD P1V0_AUX..1
(-7025 6525);
FORCEPROP 3 LASTPIN (-7025 6475) SIG_NAME P5V_AUX\g
J 0
(-7015 6485);
DISPLAY 0.659574 (-7015 6485);
PAINT MONO (-7015 6485);
DISPLAY INVISIBLE (-7015 6485);
FORCEPROP 1 LAST HDL_POWER P5V_AUX
J 1
(-7015 6565);
DISPLAY 0.617021 (-7015 6565);
PAINT GREEN (-7015 6565);
FORCEPROP 2 LAST CDS_LIB pure_quanta_power
J 0
(-7025 6525);
DISPLAY INVISIBLE (-7025 6525);
FORCEPROP 2 LAST BOM_COST VR_SYSTEM 
J 0
(-6999 6601);
DISPLAY 0.680851 (-6999 6601);
DISPLAY INVISIBLE (-6999 6601);
FORCEPROP 1 LAST PATH I46
J 0
(-6975 6550);
DISPLAY 0.872340 (-6975 6550);
PAINT AQUA (-6975 6550);
DISPLAY INVISIBLE (-6975 6550);
FORCEADD Q_RES..2
(-7025 6300);
FORCEPROP 1 LAST LOCATION R6208
J 0
(-6980 6425);
DISPLAY 0.808511 (-6980 6425);
FORCEPROP 0 LAST $SEC 1
J 0
(-6975 6475);
DISPLAY 0.680851 (-6975 6475);
PAINT MONO (-6975 6475);
DISPLAY INVISIBLE (-6975 6475);
FORCEPROP 0 LAST CDS_SEC 1
J 0
(-6975 6475);
DISPLAY 0.680851 (-6975 6475);
DISPLAY INVISIBLE (-6975 6475);
FORCEPROP 1 LASTPIN (-7025 6400) $PN 1
J 0
(-7020 6362);
DISPLAY 0.787234 (-7020 6362);
PAINT MONO (-7020 6362);
FORCEPROP 1 LASTPIN (-7025 6200) $PN 2
J 0
(-7020 6210);
DISPLAY 0.787234 (-7020 6210);
PAINT MONO (-7020 6210);
FORCEPROP 1 LAST MATERIAL CHIP
J 0
(-6985 6225);
DISPLAY 0.638298 (-6985 6225);
FORCEPROP 1 LAST WATTAGE 1/16W
J 0
(-6985 6275);
DISPLAY 0.638298 (-6985 6275);
FORCEPROP 1 LAST PACK_TYPE 0402LF
J 0
(-6985 6125);
DISPLAY 0.638298 (-6985 6125);
FORCEPROP 1 LAST TOLERANCE 1%
J 0
(-6980 6325);
DISPLAY 0.638298 (-6980 6325);
FORCEPROP 1 LAST VALUE 10K
J 0
(-6980 6375);
DISPLAY 0.638298 (-6980 6375);
FORCEPROP 2 LAST ROOM USB3_HUB1_CYP
J 0
(-6975 6475);
DISPLAY 0.680851 (-6975 6475);
PAINT RED (-6975 6475);
FORCEPROP 2 LAST CDS_LIB pure_quanta
J 0
(-7025 6300);
DISPLAY INVISIBLE (-7025 6300);
FORCEPROP 1 LAST PATH I47
J 0
(-6975 6475);
DISPLAY 0.978723 (-6975 6475);
PAINT WHITE (-6975 6475);
DISPLAY INVISIBLE (-6975 6475);
FORCEPROP 1 LAST PART_NUMBER CS31002FB08
J 0
(-6985 6175);
DISPLAY 0.638298 (-6985 6175);
DISPLAY INVISIBLE (-6985 6175);
FORCEADD Q_RES..2
(-7025 5800);
FORCEPROP 1 LAST LOCATION R6209
J 0
(-6980 5925);
DISPLAY 0.808511 (-6980 5925);
FORCEPROP 0 LAST $SEC 1
J 0
(-6975 5975);
DISPLAY 0.680851 (-6975 5975);
PAINT MONO (-6975 5975);
DISPLAY INVISIBLE (-6975 5975);
FORCEPROP 0 LAST CDS_SEC 1
J 0
(-6975 5975);
DISPLAY 0.680851 (-6975 5975);
DISPLAY INVISIBLE (-6975 5975);
FORCEPROP 1 LASTPIN (-7025 5900) $PN 1
J 0
(-7020 5862);
DISPLAY 0.787234 (-7020 5862);
PAINT MONO (-7020 5862);
FORCEPROP 1 LASTPIN (-7025 5700) $PN 2
J 0
(-7020 5710);
DISPLAY 0.787234 (-7020 5710);
PAINT MONO (-7020 5710);
FORCEPROP 1 LAST WATTAGE 1/16W
J 0
(-6985 5775);
DISPLAY 0.638298 (-6985 5775);
FORCEPROP 1 LAST TOLERANCE 1%
J 0
(-6980 5825);
DISPLAY 0.638298 (-6980 5825);
FORCEPROP 1 LAST PACK_TYPE 0402LF
J 0
(-6985 5625);
DISPLAY 0.638298 (-6985 5625);
FORCEPROP 1 LAST VALUE 10K
J 0
(-6980 5875);
DISPLAY 0.638298 (-6980 5875);
FORCEPROP 2 LAST ROOM USB3_HUB1_CYP
J 0
(-6975 5975);
DISPLAY 0.680851 (-6975 5975);
PAINT RED (-6975 5975);
FORCEPROP 1 LAST MATERIAL CHIP
J 0
(-6985 5725);
DISPLAY 0.638298 (-6985 5725);
FORCEPROP 2 LAST CDS_LIB pure_quanta
J 0
(-7025 5800);
DISPLAY INVISIBLE (-7025 5800);
FORCEPROP 1 LAST PATH I48
J 0
(-6975 5975);
DISPLAY 0.978723 (-6975 5975);
PAINT WHITE (-6975 5975);
DISPLAY INVISIBLE (-6975 5975);
FORCEPROP 1 LAST PART_NUMBER CS31002FB08
J 0
(-6985 5675);
DISPLAY 0.638298 (-6985 5675);
DISPLAY INVISIBLE (-6985 5675);
FORCEADD GND..1
(-7025 5375);
FORCEPROP 3 LASTPIN (-7025 5425) SIG_NAME GND\g
J 0
(-7015 5435);
DISPLAY 0.659574 (-7015 5435);
PAINT MONO (-7015 5435);
DISPLAY INVISIBLE (-7015 5435);
FORCEPROP 2 LAST CDS_LIB pure_quanta_power
J 0
(-7025 5375);
DISPLAY INVISIBLE (-7025 5375);
FORCEPROP 1 LAST SIZE 1B
J 0
(-6950 5325);
DISPLAY 0.872340 (-6950 5325);
PAINT GREEN (-6950 5325);
DISPLAY INVISIBLE (-6950 5325);
FORCEPROP 1 LAST HDL_POWER GND
J 0
(-7025 5525);
DISPLAY 0.872340 (-7025 5525);
PAINT GREEN (-7025 5525);
DISPLAY INVISIBLE (-7025 5525);
FORCEPROP 1 LAST PATH I49
J 0
(-6950 5375);
DISPLAY 0.872340 (-6950 5375);
PAINT AQUA (-6950 5375);
DISPLAY INVISIBLE (-6950 5375);
FORCEADD OFFPAGE..1
(-6300 5425);
FORCEPROP 2 LAST $XR0 180 
J 0
(-6552 5425);
DISPLAY 0.638298 (-6552 5425);
PAINT MONO (-6552 5425);
FORCEPROP 2 LAST CDS_LIB standard
J 0
(-6300 5425);
DISPLAY INVISIBLE (-6300 5425);
FORCEPROP 1 LAST OFFPAGE TRUE
J 0
(-5975 5300);
DISPLAY 0.872340 (-5975 5300);
PAINT GREEN (-5975 5300);
DISPLAY INVISIBLE (-5975 5300);
FORCEPROP 1 LAST COMMENT_BODY TRUE
J 0
(-6175 5325);
DISPLAY 0.872340 (-6175 5325);
PAINT GREEN (-6175 5325);
DISPLAY INVISIBLE (-6175 5325);
FORCEPROP 2 LAST PATH I5
J 0
(-6250 5500);
DISPLAY 0.680851 (-6250 5500);
DISPLAY INVISIBLE (-6250 5500);
FORCEADD OFFPAGE..1
(-7475 4425);
FORCEPROP 2 LAST $XR3 178 
J 0
(-8117 4425);
DISPLAY 0.638298 (-8117 4425);
PAINT MONO (-8117 4425);
FORCEPROP 2 LAST $XR2 176 
J 0
(-7997 4425);
DISPLAY 0.638298 (-7997 4425);
PAINT MONO (-7997 4425);
FORCEPROP 2 LAST $XR1 251 
J 0
(-7877 4425);
DISPLAY 0.638298 (-7877 4425);
PAINT MONO (-7877 4425);
FORCEPROP 2 LAST $XR0 179 
J 0
(-7757 4425);
DISPLAY 0.638298 (-7757 4425);
PAINT MONO (-7757 4425);
FORCEPROP 2 LAST CDS_LIB standard
J 0
(-7475 4425);
DISPLAY INVISIBLE (-7475 4425);
FORCEPROP 1 LAST OFFPAGE TRUE
J 0
(-7150 4300);
DISPLAY 0.872340 (-7150 4300);
PAINT GREEN (-7150 4300);
DISPLAY INVISIBLE (-7150 4300);
FORCEPROP 1 LAST COMMENT_BODY TRUE
J 0
(-7350 4325);
DISPLAY 0.872340 (-7350 4325);
PAINT GREEN (-7350 4325);
DISPLAY INVISIBLE (-7350 4325);
FORCEPROP 2 LAST PATH I55
J 0
(-7425 4500);
DISPLAY 0.680851 (-7425 4500);
DISPLAY INVISIBLE (-7425 4500);
FORCEADD OFFPAGE..3
R 2
(-7450 4525);
FORCEPROP 2 LAST $XR3 251 
J 0
(-8090 4525);
DISPLAY 0.638298 (-8090 4525);
PAINT MONO (-8090 4525);
FORCEPROP 2 LAST $XR2 179 
J 0
(-7970 4525);
DISPLAY 0.638298 (-7970 4525);
PAINT MONO (-7970 4525);
FORCEPROP 2 LAST $XR1 178 
J 0
(-7850 4525);
DISPLAY 0.638298 (-7850 4525);
PAINT MONO (-7850 4525);
FORCEPROP 2 LAST $XR0 176 
J 0
(-7730 4525);
DISPLAY 0.638298 (-7730 4525);
PAINT MONO (-7730 4525);
FORCEPROP 2 LAST CDS_LIB standard
J 0
(-7450 4525);
DISPLAY INVISIBLE (-7450 4525);
FORCEPROP 1 LAST OFFPAGE TRUE
J 2
(-7775 4400);
DISPLAY 0.872340 (-7775 4400);
PAINT GREEN (-7775 4400);
DISPLAY INVISIBLE (-7775 4400);
FORCEPROP 1 LAST COMMENT_BODY TRUE
J 2
(-7400 4425);
DISPLAY 0.872340 (-7400 4425);
PAINT GREEN (-7400 4425);
DISPLAY INVISIBLE (-7400 4425);
FORCEPROP 2 LAST PATH I56
J 0
(-7400 4600);
DISPLAY 0.680851 (-7400 4600);
DISPLAY INVISIBLE (-7400 4600);
FORCEADD OFFPAGE..2
R 2
(-6300 5625);
FORCEPROP 2 LAST $XR0 180 
J 0
(-6555 5625);
DISPLAY 0.638298 (-6555 5625);
PAINT MONO (-6555 5625);
FORCEPROP 2 LAST CDS_LIB standard
J 2
(-6300 5625);
DISPLAY INVISIBLE (-6300 5625);
FORCEPROP 1 LAST OFFPAGE TRUE
J 2
(-6625 5500);
DISPLAY 0.872340 (-6625 5500);
PAINT GREEN (-6625 5500);
DISPLAY INVISIBLE (-6625 5500);
FORCEPROP 1 LAST COMMENT_BODY TRUE
J 2
(-6255 5530);
DISPLAY 0.872340 (-6255 5530);
PAINT GREEN (-6255 5530);
DISPLAY INVISIBLE (-6255 5530);
FORCEPROP 2 LAST PATH I6
J 2
(-6475 5700);
DISPLAY 0.680851 (-6475 5700);
DISPLAY INVISIBLE (-6475 5700);
FORCEADD GND..1
(-3300 500);
FORCEPROP 3 LASTPIN (-3300 550) SIG_NAME GND\g
J 0
(-3290 560);
DISPLAY 0.659574 (-3290 560);
PAINT MONO (-3290 560);
DISPLAY INVISIBLE (-3290 560);
FORCEPROP 2 LAST CDS_LIB pure_quanta_power
J 0
(-3300 500);
DISPLAY INVISIBLE (-3300 500);
FORCEPROP 1 LAST SIZE 1B
J 0
(-3225 450);
DISPLAY 0.872340 (-3225 450);
PAINT GREEN (-3225 450);
DISPLAY INVISIBLE (-3225 450);
FORCEPROP 1 LAST HDL_POWER GND
J 0
(-3300 650);
DISPLAY 0.872340 (-3300 650);
PAINT GREEN (-3300 650);
DISPLAY INVISIBLE (-3300 650);
FORCEPROP 1 LAST PATH I61
J 0
(-3225 500);
DISPLAY 0.872340 (-3225 500);
PAINT AQUA (-3225 500);
DISPLAY INVISIBLE (-3225 500);
FORCEADD GND..1
(-2850 475);
FORCEPROP 3 LASTPIN (-2850 525) SIG_NAME GND\g
J 0
(-2840 535);
DISPLAY 0.659574 (-2840 535);
PAINT MONO (-2840 535);
DISPLAY INVISIBLE (-2840 535);
FORCEPROP 1 LAST SIZE 1B
J 0
(-2775 425);
DISPLAY 0.872340 (-2775 425);
PAINT GREEN (-2775 425);
DISPLAY INVISIBLE (-2775 425);
FORCEPROP 2 LAST CDS_LIB pure_quanta_power
J 0
(-2850 475);
DISPLAY INVISIBLE (-2850 475);
FORCEPROP 1 LAST HDL_POWER GND
J 0
(-2850 625);
DISPLAY 0.872340 (-2850 625);
PAINT GREEN (-2850 625);
DISPLAY INVISIBLE (-2850 625);
FORCEPROP 1 LAST PATH I62
J 0
(-2775 475);
DISPLAY 0.872340 (-2775 475);
PAINT AQUA (-2775 475);
DISPLAY INVISIBLE (-2775 475);
FORCEADD UNIVERSAL_POWER..1
(-3100 1525);
FORCEPROP 3 LASTPIN (-3100 1475) SIG_NAME P3V3_AUX\g
J 0
(-3090 1485);
DISPLAY 0.659574 (-3090 1485);
PAINT MONO (-3090 1485);
DISPLAY INVISIBLE (-3090 1485);
FORCEPROP 1 LAST HDL_POWER P3V3_AUX
J 1
(-3100 1575);
DISPLAY 0.489362 (-3100 1575);
PAINT GREEN (-3100 1575);
FORCEPROP 2 LAST CDS_LIB pure_quanta_power
J 0
(-3100 1525);
DISPLAY INVISIBLE (-3100 1525);
FORCEPROP 2 LAST BOM_COST VR_SYSTEM
J 0
(-3100 1625);
DISPLAY 0.617021 (-3100 1625);
PAINT PURPLE (-3100 1625);
DISPLAY INVISIBLE (-3100 1625);
FORCEPROP 1 LAST PATH I63
J 0
(-3050 1550);
DISPLAY 0.872340 (-3050 1550);
PAINT AQUA (-3050 1550);
DISPLAY INVISIBLE (-3050 1550);
FORCEADD M24128BWMN6TP..1
(-2050 2825);
FORCEPROP 1 LAST LOCATION U6003
J 0
(-2204 3240);
DISPLAY 0.723404 (-2204 3240);
PAINT GREEN (-2204 3240);
FORCEPROP 2 LAST SEC 1
J 0
(-2200 3375);
DISPLAY 0.680851 (-2200 3375);
PAINT MONO (-2200 3375);
DISPLAY INVISIBLE (-2200 3375);
FORCEPROP 2 LASTPIN (-1750 2900) $PN 1
J 0
(-1740 2910);
DISPLAY 0.680851 (-1740 2910);
PAINT MONO (-1740 2910);
FORCEPROP 2 LASTPIN (-1750 2850) $PN 2
J 0
(-1740 2860);
DISPLAY 0.680851 (-1740 2860);
PAINT MONO (-1740 2860);
FORCEPROP 2 LASTPIN (-1750 2800) $PN 3
J 0
(-1740 2810);
DISPLAY 0.680851 (-1740 2810);
PAINT MONO (-1740 2810);
FORCEPROP 2 LASTPIN (-2350 2800) $PN 6
J 2
(-2360 2810);
DISPLAY 0.680851 (-2360 2810);
PAINT MONO (-2360 2810);
FORCEPROP 2 LASTPIN (-2350 2750) $PN 5
J 2
(-2360 2760);
DISPLAY 0.680851 (-2360 2760);
PAINT MONO (-2360 2760);
FORCEPROP 2 LASTPIN (-2350 2900) $PN 8
J 2
(-2360 2910);
DISPLAY 0.680851 (-2360 2910);
PAINT MONO (-2360 2910);
FORCEPROP 2 LASTPIN (-1750 2750) $PN 4
J 0
(-1740 2760);
DISPLAY 0.680851 (-1740 2760);
PAINT MONO (-1740 2760);
FORCEPROP 2 LASTPIN (-2350 2850) $PN 7
J 2
(-2360 2860);
DISPLAY 0.680851 (-2360 2860);
PAINT MONO (-2360 2860);
FORCEPROP 2 LAST VALUE M24128-BWMN6TP
J 0
(-2200 3275);
DISPLAY 0.680851 (-2200 3275);
FORCEPROP 2 LAST ROOM USB3_HUB1_CYP
J 0
(-2200 3375);
DISPLAY 0.680851 (-2200 3375);
PAINT RED (-2200 3375);
FORCEPROP 2 LAST PART_TYPE SMLF
J 0
(-2200 3325);
DISPLAY 0.680851 (-2200 3325);
FORCEPROP 1 LAST MATERIAL IC
J 0
(-2204 2966);
DISPLAY 0.723404 (-2204 2966);
PAINT GREEN (-2204 2966);
FORCEPROP 2 LAST CDS_LIB pure_quanta
J 0
(-2050 2825);
DISPLAY INVISIBLE (-2050 2825);
FORCEPROP 1 LAST NEEDS_NO_SIZE TRUE
J 0
(-2050 2825);
DISPLAY 0.723404 (-2050 2825);
PAINT GREEN (-2050 2825);
DISPLAY INVISIBLE (-2050 2825);
FORCEPROP 1 LAST CDS_LMAN_SYM_OUTLINE -150,125,150,-125
J 0
(-2050 2825);
DISPLAY 0.468085 (-2050 2825);
PAINT GREEN (-2050 2825);
DISPLAY INVISIBLE (-2050 2825);
FORCEPROP 2 LAST SEC_TYPE 
J 0
(-2200 3375);
DISPLAY 0.680851 (-2200 3375);
DISPLAY INVISIBLE (-2200 3375);
FORCEPROP 1 LAST PATH I64
J 0
(-2050 2825);
DISPLAY 0.723404 (-2050 2825);
PAINT GREEN (-2050 2825);
DISPLAY INVISIBLE (-2050 2825);
FORCEPROP 1 LAST PART_NUMBER AKE30Z00613
J 0
(-2204 3093);
DISPLAY 0.723404 (-2204 3093);
PAINT GREEN (-2204 3093);
DISPLAY INVISIBLE (-2204 3093);
FORCEADD Q_RES..2
R 2
(-1050 3225);
FORCEPROP 1 LAST LOCATION R6222
J 2
(-1095 3350);
DISPLAY 0.808511 (-1095 3350);
FORCEPROP 0 LAST $SEC 1
J 0
(-1075 3400);
DISPLAY 0.680851 (-1075 3400);
PAINT MONO (-1075 3400);
DISPLAY INVISIBLE (-1075 3400);
FORCEPROP 0 LAST CDS_SEC 1
J 0
(-1075 3400);
DISPLAY 0.680851 (-1075 3400);
DISPLAY INVISIBLE (-1075 3400);
FORCEPROP 1 LASTPIN (-1050 3325) $PN 1
J 2
(-1055 3287);
DISPLAY 0.787234 (-1055 3287);
PAINT MONO (-1055 3287);
FORCEPROP 1 LASTPIN (-1050 3125) $PN 2
J 2
(-1055 3135);
DISPLAY 0.787234 (-1055 3135);
PAINT MONO (-1055 3135);
FORCEPROP 1 LAST MATERIAL CHIP
J 2
(-1090 3150);
DISPLAY 0.638298 (-1090 3150);
FORCEPROP 1 LAST WATTAGE 1/16W
J 2
(-1090 3200);
DISPLAY 0.638298 (-1090 3200);
FORCEPROP 1 LAST TOLERANCE 1%
J 2
(-1095 3250);
DISPLAY 0.638298 (-1095 3250);
FORCEPROP 2 LAST ROOM USB3_HUB1_CYP
J 0
(-1450 3400);
DISPLAY 0.553191 (-1450 3400);
PAINT RED (-1450 3400);
FORCEPROP 1 LAST VALUE 10K
J 2
(-1095 3300);
DISPLAY 0.638298 (-1095 3300);
FORCEPROP 1 LAST PACK_TYPE 0402LF
J 2
(-1090 3050);
DISPLAY 0.638298 (-1090 3050);
FORCEPROP 2 LAST CDS_LIB pure_quanta
J 2
(-1050 3225);
DISPLAY INVISIBLE (-1050 3225);
FORCEPROP 1 LAST PATH I65
J 2
(-1100 3400);
DISPLAY 0.978723 (-1100 3400);
PAINT WHITE (-1100 3400);
DISPLAY INVISIBLE (-1100 3400);
FORCEPROP 1 LAST PART_NUMBER CS31002FB08
J 2
(-1090 3100);
DISPLAY 0.638298 (-1090 3100);
DISPLAY INVISIBLE (-1090 3100);
FORCEADD Q_RES..2
(-850 2375);
FORCEPROP 1 LAST LOCATION R6219
J 0
(-805 2500);
DISPLAY 0.808511 (-805 2500);
FORCEPROP 0 LAST $SEC 1
J 0
(-800 2550);
DISPLAY 0.680851 (-800 2550);
PAINT MONO (-800 2550);
DISPLAY INVISIBLE (-800 2550);
FORCEPROP 0 LAST CDS_SEC 1
J 0
(-800 2550);
DISPLAY 0.680851 (-800 2550);
DISPLAY INVISIBLE (-800 2550);
FORCEPROP 1 LASTPIN (-850 2475) $PN 1
J 0
(-845 2437);
DISPLAY 0.787234 (-845 2437);
PAINT MONO (-845 2437);
FORCEPROP 1 LASTPIN (-850 2275) $PN 2
J 0
(-845 2285);
DISPLAY 0.787234 (-845 2285);
PAINT MONO (-845 2285);
FORCEPROP 1 LAST PACK_TYPE 0402LF
J 0
(-810 2200);
DISPLAY 0.638298 (-810 2200);
FORCEPROP 1 LAST MATERIAL CHIP
J 0
(-810 2300);
DISPLAY 0.638298 (-810 2300);
FORCEPROP 1 LAST WATTAGE 1/16W
J 0
(-810 2350);
DISPLAY 0.638298 (-810 2350);
FORCEPROP 1 LAST TOLERANCE 1%
J 0
(-805 2400);
DISPLAY 0.638298 (-805 2400);
FORCEPROP 1 LAST VALUE 10K
J 0
(-805 2450);
DISPLAY 0.638298 (-805 2450);
FORCEPROP 2 LAST ROOM USB3_HUB1_CYP
J 0
(-800 2550);
DISPLAY 0.446809 (-800 2550);
PAINT RED (-800 2550);
FORCEPROP 2 LAST CDS_LIB pure_quanta
J 0
(-850 2375);
DISPLAY INVISIBLE (-850 2375);
FORCEPROP 1 LAST PATH I66
J 0
(-800 2550);
DISPLAY 0.978723 (-800 2550);
PAINT WHITE (-800 2550);
DISPLAY INVISIBLE (-800 2550);
FORCEPROP 1 LAST PART_NUMBER CS31002FB08
J 0
(-810 2250);
DISPLAY 0.638298 (-810 2250);
DISPLAY INVISIBLE (-810 2250);
FORCEADD Q_RES..2
(-450 2375);
FORCEPROP 1 LAST LOCATION R6221
J 0
(-405 2500);
DISPLAY 0.808511 (-405 2500);
FORCEPROP 0 LAST $SEC 1
J 0
(-400 2550);
DISPLAY 0.680851 (-400 2550);
PAINT MONO (-400 2550);
DISPLAY INVISIBLE (-400 2550);
FORCEPROP 0 LAST CDS_SEC 1
J 0
(-400 2550);
DISPLAY 0.680851 (-400 2550);
DISPLAY INVISIBLE (-400 2550);
FORCEPROP 1 LASTPIN (-450 2475) $PN 1
J 0
(-445 2437);
DISPLAY 0.787234 (-445 2437);
PAINT MONO (-445 2437);
FORCEPROP 1 LASTPIN (-450 2275) $PN 2
J 0
(-445 2285);
DISPLAY 0.787234 (-445 2285);
PAINT MONO (-445 2285);
FORCEPROP 1 LAST PACK_TYPE 0402LF
J 0
(-410 2200);
DISPLAY 0.638298 (-410 2200);
FORCEPROP 1 LAST TOLERANCE 1%
J 0
(-405 2400);
DISPLAY 0.638298 (-405 2400);
FORCEPROP 1 LAST MATERIAL CHIP
J 0
(-410 2300);
DISPLAY 0.638298 (-410 2300);
FORCEPROP 1 LAST WATTAGE 1/16W
J 0
(-410 2350);
DISPLAY 0.638298 (-410 2350);
FORCEPROP 1 LAST VALUE 10K
J 0
(-405 2450);
DISPLAY 0.638298 (-405 2450);
FORCEPROP 2 LAST ROOM USB3_HUB1_CYP
J 0
(-400 2550);
DISPLAY 0.446809 (-400 2550);
PAINT RED (-400 2550);
FORCEPROP 2 LAST CDS_LIB pure_quanta
J 0
(-450 2375);
DISPLAY INVISIBLE (-450 2375);
FORCEPROP 1 LAST PATH I67
J 0
(-400 2550);
DISPLAY 0.978723 (-400 2550);
PAINT WHITE (-400 2550);
DISPLAY INVISIBLE (-400 2550);
FORCEPROP 1 LAST PART_NUMBER CS31002FB08
J 0
(-410 2250);
DISPLAY 0.638298 (-410 2250);
DISPLAY INVISIBLE (-410 2250);
FORCEADD Q_RES..2
R 2
(-1050 2400);
FORCEPROP 1 LAST LOCATION R6217
J 2
(-1095 2525);
DISPLAY 0.638298 (-1095 2525);
FORCEPROP 0 LAST $SEC 1
J 0
(-1075 2575);
DISPLAY 0.680851 (-1075 2575);
PAINT MONO (-1075 2575);
DISPLAY INVISIBLE (-1075 2575);
FORCEPROP 0 LAST CDS_SEC 1
J 0
(-1075 2575);
DISPLAY 0.680851 (-1075 2575);
DISPLAY INVISIBLE (-1075 2575);
FORCEPROP 1 LASTPIN (-1050 2500) $PN 1
J 2
(-1055 2462);
DISPLAY 0.787234 (-1055 2462);
PAINT MONO (-1055 2462);
FORCEPROP 1 LASTPIN (-1050 2300) $PN 2
J 2
(-1055 2310);
DISPLAY 0.787234 (-1055 2310);
PAINT MONO (-1055 2310);
FORCEPROP 2 LAST ROOM USB3_HUB1_CYP
J 0
(-1450 2575);
DISPLAY 0.553191 (-1450 2575);
PAINT RED (-1450 2575);
FORCEPROP 1 LAST VALUE 10K
J 2
(-1095 2475);
DISPLAY 0.638298 (-1095 2475);
FORCEPROP 1 LAST WATTAGE 1/16W
J 2
(-1090 2375);
DISPLAY 0.638298 (-1090 2375);
FORCEPROP 1 LAST PACK_TYPE 0402LF
J 2
(-1090 2225);
DISPLAY 0.638298 (-1090 2225);
FORCEPROP 1 LAST TOLERANCE 1%
J 2
(-1095 2425);
DISPLAY 0.638298 (-1095 2425);
FORCEPROP 1 LAST MATERIAL EMPTY
J 2
(-1090 2325);
DISPLAY 0.638298 (-1090 2325);
FORCEPROP 2 LAST CDS_LIB pure_quanta
J 2
(-1050 2400);
DISPLAY INVISIBLE (-1050 2400);
FORCEPROP 1 LAST PATH I68
J 2
(-1100 2575);
DISPLAY 0.978723 (-1100 2575);
PAINT WHITE (-1100 2575);
DISPLAY INVISIBLE (-1100 2575);
FORCEPROP 1 LAST PART_NUMBER CS31002FB08
J 2
(-1090 2275);
DISPLAY 0.638298 (-1090 2275);
DISPLAY INVISIBLE (-1090 2275);
FORCEADD Q_RES..2
(-850 3200);
FORCEPROP 1 LAST LOCATION R6218
J 0
(-805 3325);
DISPLAY 0.638298 (-805 3325);
FORCEPROP 0 LAST $SEC 1
J 0
(-800 3375);
DISPLAY 0.680851 (-800 3375);
PAINT MONO (-800 3375);
DISPLAY INVISIBLE (-800 3375);
FORCEPROP 0 LAST CDS_SEC 1
J 0
(-800 3375);
DISPLAY 0.680851 (-800 3375);
DISPLAY INVISIBLE (-800 3375);
FORCEPROP 1 LASTPIN (-850 3300) $PN 1
J 0
(-845 3262);
DISPLAY 0.787234 (-845 3262);
PAINT MONO (-845 3262);
FORCEPROP 1 LASTPIN (-850 3100) $PN 2
J 0
(-845 3110);
DISPLAY 0.787234 (-845 3110);
PAINT MONO (-845 3110);
FORCEPROP 2 LAST ROOM USB3_HUB1_CYP
J 0
(-800 3375);
DISPLAY 0.446809 (-800 3375);
PAINT RED (-800 3375);
FORCEPROP 1 LAST TOLERANCE 1%
J 0
(-805 3225);
DISPLAY 0.638298 (-805 3225);
FORCEPROP 1 LAST WATTAGE 1/16W
J 0
(-810 3175);
DISPLAY 0.638298 (-810 3175);
FORCEPROP 1 LAST MATERIAL EMPTY
J 0
(-810 3125);
DISPLAY 0.638298 (-810 3125);
FORCEPROP 1 LAST VALUE 10K
J 0
(-805 3275);
DISPLAY 0.638298 (-805 3275);
FORCEPROP 1 LAST PACK_TYPE 0402LF
J 0
(-810 3025);
DISPLAY 0.638298 (-810 3025);
FORCEPROP 2 LAST CDS_LIB pure_quanta
J 0
(-850 3200);
DISPLAY INVISIBLE (-850 3200);
FORCEPROP 1 LAST PATH I69
J 0
(-800 3375);
DISPLAY 0.978723 (-800 3375);
PAINT WHITE (-800 3375);
DISPLAY INVISIBLE (-800 3375);
FORCEPROP 1 LAST PART_NUMBER CS31002FB08
J 0
(-810 3075);
DISPLAY 0.638298 (-810 3075);
DISPLAY INVISIBLE (-810 3075);
FORCEADD OFFPAGE..2
R 2
(-6300 5575);
FORCEPROP 2 LAST $XR0 180 
J 0
(-6555 5575);
DISPLAY 0.638298 (-6555 5575);
PAINT MONO (-6555 5575);
FORCEPROP 2 LAST CDS_LIB standard
J 0
(-6300 5575);
DISPLAY INVISIBLE (-6300 5575);
FORCEPROP 1 LAST OFFPAGE TRUE
J 2
(-6625 5450);
DISPLAY 0.872340 (-6625 5450);
PAINT GREEN (-6625 5450);
DISPLAY INVISIBLE (-6625 5450);
FORCEPROP 1 LAST COMMENT_BODY TRUE
J 2
(-6255 5480);
DISPLAY 0.872340 (-6255 5480);
PAINT GREEN (-6255 5480);
DISPLAY INVISIBLE (-6255 5480);
FORCEPROP 2 LAST PATH I7
J 0
(-6250 5650);
DISPLAY 0.680851 (-6250 5650);
DISPLAY INVISIBLE (-6250 5650);
FORCEADD Q_RES..2
(-450 3200);
FORCEPROP 1 LAST LOCATION R6220
J 0
(-405 3325);
DISPLAY 0.638298 (-405 3325);
FORCEPROP 0 LAST $SEC 1
J 0
(-400 3375);
DISPLAY 0.680851 (-400 3375);
PAINT MONO (-400 3375);
DISPLAY INVISIBLE (-400 3375);
FORCEPROP 0 LAST CDS_SEC 1
J 0
(-400 3375);
DISPLAY 0.680851 (-400 3375);
DISPLAY INVISIBLE (-400 3375);
FORCEPROP 1 LASTPIN (-450 3300) $PN 1
J 0
(-445 3262);
DISPLAY 0.787234 (-445 3262);
PAINT MONO (-445 3262);
FORCEPROP 1 LASTPIN (-450 3100) $PN 2
J 0
(-445 3110);
DISPLAY 0.787234 (-445 3110);
PAINT MONO (-445 3110);
FORCEPROP 1 LAST TOLERANCE 1%
J 0
(-405 3225);
DISPLAY 0.638298 (-405 3225);
FORCEPROP 1 LAST VALUE 10K
J 0
(-405 3275);
DISPLAY 0.638298 (-405 3275);
FORCEPROP 1 LAST PACK_TYPE 0402LF
J 0
(-410 3025);
DISPLAY 0.638298 (-410 3025);
FORCEPROP 1 LAST MATERIAL EMPTY
J 0
(-410 3125);
DISPLAY 0.638298 (-410 3125);
FORCEPROP 1 LAST WATTAGE 1/16W
J 0
(-410 3175);
DISPLAY 0.638298 (-410 3175);
FORCEPROP 2 LAST ROOM USB3_HUB1_CYP
J 0
(-400 3375);
DISPLAY 0.446809 (-400 3375);
PAINT RED (-400 3375);
FORCEPROP 2 LAST CDS_LIB pure_quanta
J 0
(-450 3200);
DISPLAY INVISIBLE (-450 3200);
FORCEPROP 1 LAST PATH I70
J 0
(-400 3375);
DISPLAY 0.978723 (-400 3375);
PAINT WHITE (-400 3375);
DISPLAY INVISIBLE (-400 3375);
FORCEPROP 1 LAST PART_NUMBER CS31002FB08
J 0
(-410 3075);
DISPLAY 0.638298 (-410 3075);
DISPLAY INVISIBLE (-410 3075);
FORCEADD GND..1
(-1050 1925);
FORCEPROP 3 LASTPIN (-1050 1975) SIG_NAME GND\g
J 0
(-1040 1985);
DISPLAY 0.659574 (-1040 1985);
PAINT MONO (-1040 1985);
DISPLAY INVISIBLE (-1040 1985);
FORCEPROP 2 LAST CDS_LIB pure_quanta_power
J 0
(-1050 1925);
DISPLAY INVISIBLE (-1050 1925);
FORCEPROP 1 LAST SIZE 1B
J 0
(-975 1875);
DISPLAY 0.872340 (-975 1875);
PAINT GREEN (-975 1875);
DISPLAY INVISIBLE (-975 1875);
FORCEPROP 1 LAST HDL_POWER GND
J 0
(-1050 2075);
DISPLAY 0.872340 (-1050 2075);
PAINT GREEN (-1050 2075);
DISPLAY INVISIBLE (-1050 2075);
FORCEPROP 1 LAST PATH I71
J 0
(-975 1925);
DISPLAY 0.872340 (-975 1925);
PAINT AQUA (-975 1925);
DISPLAY INVISIBLE (-975 1925);
FORCEADD UNIVERSAL_POWER..1
(-1050 3775);
FORCEPROP 3 LASTPIN (-1050 3725) SIG_NAME P3V3_AUX\g
J 0
(-1040 3735);
DISPLAY 0.659574 (-1040 3735);
PAINT MONO (-1040 3735);
DISPLAY INVISIBLE (-1040 3735);
FORCEPROP 1 LAST HDL_POWER P3V3_AUX
J 1
(-1050 3825);
DISPLAY 0.489362 (-1050 3825);
PAINT GREEN (-1050 3825);
FORCEPROP 2 LAST BOM_COST VR_SYSTEM
J 0
(-1050 3875);
DISPLAY 0.617021 (-1050 3875);
PAINT PURPLE (-1050 3875);
DISPLAY INVISIBLE (-1050 3875);
FORCEPROP 2 LAST CDS_LIB pure_quanta_power
J 0
(-1050 3775);
DISPLAY INVISIBLE (-1050 3775);
FORCEPROP 1 LAST PATH I72
J 0
(-1000 3800);
DISPLAY 0.872340 (-1000 3800);
PAINT AQUA (-1000 3800);
DISPLAY INVISIBLE (-1000 3800);
FORCEADD GND..1
(-1550 2625);
FORCEPROP 3 LASTPIN (-1550 2675) SIG_NAME GND\g
J 0
(-1540 2685);
DISPLAY 0.659574 (-1540 2685);
PAINT MONO (-1540 2685);
DISPLAY INVISIBLE (-1540 2685);
FORCEPROP 1 LAST SIZE 1B
J 0
(-1475 2575);
DISPLAY 0.872340 (-1475 2575);
PAINT GREEN (-1475 2575);
DISPLAY INVISIBLE (-1475 2575);
FORCEPROP 2 LAST CDS_LIB pure_quanta_power
J 0
(-1550 2625);
DISPLAY INVISIBLE (-1550 2625);
FORCEPROP 1 LAST HDL_POWER GND
J 0
(-1550 2775);
DISPLAY 0.872340 (-1550 2775);
PAINT GREEN (-1550 2775);
DISPLAY INVISIBLE (-1550 2775);
FORCEPROP 1 LAST PATH I73
J 0
(-1475 2625);
DISPLAY 0.872340 (-1475 2625);
PAINT AQUA (-1475 2625);
DISPLAY INVISIBLE (-1475 2625);
FORCEADD UNIVERSAL_POWER..1
(-2425 3575);
FORCEPROP 3 LASTPIN (-2425 3525) SIG_NAME P3V3_AUX\g
J 0
(-2415 3535);
DISPLAY 0.659574 (-2415 3535);
PAINT MONO (-2415 3535);
DISPLAY INVISIBLE (-2415 3535);
FORCEPROP 1 LAST HDL_POWER P3V3_AUX
J 1
(-2425 3625);
DISPLAY 0.489362 (-2425 3625);
PAINT GREEN (-2425 3625);
FORCEPROP 2 LAST BOM_COST VR_SYSTEM
J 0
(-2425 3675);
DISPLAY 0.617021 (-2425 3675);
PAINT PURPLE (-2425 3675);
DISPLAY INVISIBLE (-2425 3675);
FORCEPROP 2 LAST CDS_LIB pure_quanta_power
J 0
(-2425 3575);
DISPLAY INVISIBLE (-2425 3575);
FORCEPROP 1 LAST PATH I74
J 0
(-2375 3600);
DISPLAY 0.872340 (-2375 3600);
PAINT AQUA (-2375 3600);
DISPLAY INVISIBLE (-2375 3600);
FORCEADD Q_CAP..1
(-2650 3325);
FORCEPROP 1 LAST LOCATION C6083
J 0
(-2600 3425);
DISPLAY 0.638298 (-2600 3425);
FORCEPROP 0 LAST $SEC 1
J 0
(-2600 3475);
DISPLAY 0.680851 (-2600 3475);
PAINT MONO (-2600 3475);
DISPLAY INVISIBLE (-2600 3475);
FORCEPROP 0 LAST CDS_SEC 1
J 0
(-2600 3475);
DISPLAY 0.680851 (-2600 3475);
DISPLAY INVISIBLE (-2600 3475);
FORCEPROP 1 LASTPIN (-2650 3425) $PN 1
J 0
(-2640 3405);
DISPLAY 0.787234 (-2640 3405);
PAINT MONO (-2640 3405);
FORCEPROP 1 LASTPIN (-2650 3225) $PN 2
J 0
(-2640 3205);
DISPLAY 0.787234 (-2640 3205);
PAINT MONO (-2640 3205);
FORCEPROP 2 LAST ROOM USB3_HUB1_CYP
J 0
(-2625 3175);
DISPLAY 0.297872 (-2625 3175);
PAINT RED (-2625 3175);
FORCEPROP 1 LAST VALUE 0.1UF
J 0
(-2600 3375);
DISPLAY 0.510638 (-2600 3375);
FORCEPROP 1 LAST VOLTAGE 25V
J 0
(-2600 3325);
DISPLAY 0.510638 (-2600 3325);
FORCEPROP 1 LAST TOLERANCE 10%
J 0
(-2600 3275);
DISPLAY 0.510638 (-2600 3275);
FORCEPROP 1 LAST MATERIAL X7R
J 0
(-2600 3225);
DISPLAY 0.510638 (-2600 3225);
FORCEPROP 1 LAST PACK_TYPE 0402
J 0
(-2600 3125);
DISPLAY 0.510638 (-2600 3125);
FORCEPROP 2 LAST CDS_LIB pure_quanta
J 0
(-2650 3325);
DISPLAY INVISIBLE (-2650 3325);
FORCEPROP 1 LAST PATH I75
J 0
(-2600 3475);
DISPLAY 0.978723 (-2600 3475);
PAINT WHITE (-2600 3475);
DISPLAY INVISIBLE (-2600 3475);
FORCEPROP 1 LAST PART_NUMBER CH4104K1B00
J 0
(-2600 3175);
DISPLAY 0.808511 (-2600 3175);
DISPLAY INVISIBLE (-2600 3175);
FORCEADD GND..1
(-2650 3075);
FORCEPROP 3 LASTPIN (-2650 3125) SIG_NAME GND\g
J 0
(-2640 3135);
DISPLAY 0.659574 (-2640 3135);
PAINT MONO (-2640 3135);
DISPLAY INVISIBLE (-2640 3135);
FORCEPROP 2 LAST CDS_LIB pure_quanta_power
J 0
(-2650 3075);
DISPLAY INVISIBLE (-2650 3075);
FORCEPROP 1 LAST SIZE 1B
J 0
(-2575 3025);
DISPLAY 0.872340 (-2575 3025);
PAINT GREEN (-2575 3025);
DISPLAY INVISIBLE (-2575 3025);
FORCEPROP 1 LAST HDL_POWER GND
J 0
(-2650 3225);
DISPLAY 0.872340 (-2650 3225);
PAINT GREEN (-2650 3225);
DISPLAY INVISIBLE (-2650 3225);
FORCEPROP 1 LAST PATH I76
J 0
(-2575 3075);
DISPLAY 0.872340 (-2575 3075);
PAINT AQUA (-2575 3075);
DISPLAY INVISIBLE (-2575 3075);
FORCEADD Q_RES..2
R 2
(-2700 2425);
FORCEPROP 1 LAST LOCATION R6223
J 2
(-2500 2550);
DISPLAY 0.787234 (-2500 2550);
FORCEPROP 0 LAST $SEC 1
J 0
(-2500 2600);
DISPLAY 0.680851 (-2500 2600);
PAINT MONO (-2500 2600);
DISPLAY INVISIBLE (-2500 2600);
FORCEPROP 0 LAST CDS_SEC 1
J 0
(-2500 2600);
DISPLAY 0.680851 (-2500 2600);
DISPLAY INVISIBLE (-2500 2600);
FORCEPROP 1 LASTPIN (-2700 2525) $PN 1
J 2
(-2705 2487);
DISPLAY 0.787234 (-2705 2487);
PAINT MONO (-2705 2487);
FORCEPROP 1 LASTPIN (-2700 2325) $PN 2
J 2
(-2705 2335);
DISPLAY 0.787234 (-2705 2335);
PAINT MONO (-2705 2335);
FORCEPROP 1 LAST PACK_TYPE 0402LF
J 0
(-2650 2250);
DISPLAY 0.617021 (-2650 2250);
FORCEPROP 2 LAST ROOM USB3_HUB1_CYP
J 0
(-2650 2600);
DISPLAY 0.680851 (-2650 2600);
PAINT RED (-2650 2600);
FORCEPROP 1 LAST VALUE 1K
J 0
(-2650 2500);
DISPLAY 0.617021 (-2650 2500);
FORCEPROP 1 LAST TOLERANCE 1%
J 0
(-2650 2450);
DISPLAY 0.617021 (-2650 2450);
FORCEPROP 1 LAST WATTAGE 1/16W
J 0
(-2650 2400);
DISPLAY 0.617021 (-2650 2400);
FORCEPROP 1 LAST MATERIAL CHIP
J 0
(-2650 2350);
DISPLAY 0.617021 (-2650 2350);
FORCEPROP 2 LAST BOM_COST VR_SYSTEM 
J 2
(-2650 2575);
DISPLAY 0.680851 (-2650 2575);
DISPLAY INVISIBLE (-2650 2575);
FORCEPROP 2 LAST REUSE_ID 3
J 2
(-2650 2625);
DISPLAY 0.680851 (-2650 2625);
DISPLAY INVISIBLE (-2650 2625);
FORCEPROP 2 LAST CDS_LIB pure_quanta
J 2
(-2700 2425);
DISPLAY INVISIBLE (-2700 2425);
FORCEPROP 1 LAST PATH I77
J 2
(-2750 2600);
DISPLAY 0.978723 (-2750 2600);
PAINT WHITE (-2750 2600);
DISPLAY INVISIBLE (-2750 2600);
FORCEPROP 1 LAST PART_NUMBER CS21002FB06
J 0
(-2650 2300);
DISPLAY 0.617021 (-2650 2300);
DISPLAY INVISIBLE (-2650 2300);
FORCEADD GND..1
(-2700 2125);
FORCEPROP 3 LASTPIN (-2700 2175) SIG_NAME GND\g
J 0
(-2690 2185);
DISPLAY 0.659574 (-2690 2185);
PAINT MONO (-2690 2185);
DISPLAY INVISIBLE (-2690 2185);
FORCEPROP 2 LAST CDS_LIB pure_quanta_power
J 0
(-2700 2125);
DISPLAY INVISIBLE (-2700 2125);
FORCEPROP 1 LAST SIZE 1B
J 0
(-2625 2075);
DISPLAY 0.872340 (-2625 2075);
PAINT GREEN (-2625 2075);
DISPLAY INVISIBLE (-2625 2075);
FORCEPROP 1 LAST HDL_POWER GND
J 0
(-2700 2275);
DISPLAY 0.872340 (-2700 2275);
PAINT GREEN (-2700 2275);
DISPLAY INVISIBLE (-2700 2275);
FORCEPROP 1 LAST PATH I78
J 0
(-2625 2125);
DISPLAY 0.872340 (-2625 2125);
PAINT AQUA (-2625 2125);
DISPLAY INVISIBLE (-2625 2125);
FORCEADD OFFPAGE..3
(-3025 5775);
FORCEPROP 2 LAST $XR0 180 
J 0
(-2811 5775);
DISPLAY 0.638298 (-2811 5775);
PAINT MONO (-2811 5775);
FORCEPROP 2 LAST CDS_LIB standard
J 2
(-3025 5775);
DISPLAY INVISIBLE (-3025 5775);
FORCEPROP 1 LAST OFFPAGE TRUE
J 0
(-2700 5650);
DISPLAY 0.872340 (-2700 5650);
PAINT GREEN (-2700 5650);
DISPLAY INVISIBLE (-2700 5650);
FORCEPROP 1 LAST COMMENT_BODY TRUE
J 0
(-3075 5675);
DISPLAY 0.872340 (-3075 5675);
PAINT GREEN (-3075 5675);
DISPLAY INVISIBLE (-3075 5675);
FORCEPROP 2 LAST PATH I8
J 2
(-3075 5850);
DISPLAY 0.680851 (-3075 5850);
DISPLAY INVISIBLE (-3075 5850);
FORCEADD OFFPAGE..1
(-3825 2800);
FORCEPROP 2 LAST $XR3 178 
J 0
(-4251 2800);
DISPLAY 0.638298 (-4251 2800);
PAINT MONO (-4251 2800);
FORCEPROP 2 LAST $XR2 176 
J 0
(-4251 2800);
DISPLAY 0.638298 (-4251 2800);
PAINT MONO (-4251 2800);
FORCEPROP 2 LAST $XR1 251 
J 0
(-4251 2800);
DISPLAY 0.638298 (-4251 2800);
PAINT MONO (-4251 2800);
FORCEPROP 2 LAST $XR0 179 
J 0
(-4251 2800);
DISPLAY 0.638298 (-4251 2800);
PAINT MONO (-4251 2800);
FORCEPROP 2 LAST CDS_LIB standard
J 0
(-3825 2800);
DISPLAY INVISIBLE (-3825 2800);
FORCEPROP 1 LAST OFFPAGE TRUE
J 0
(-3500 2675);
DISPLAY 0.872340 (-3500 2675);
PAINT GREEN (-3500 2675);
DISPLAY INVISIBLE (-3500 2675);
FORCEPROP 1 LAST COMMENT_BODY TRUE
J 0
(-3700 2700);
DISPLAY 0.872340 (-3700 2700);
PAINT GREEN (-3700 2700);
DISPLAY INVISIBLE (-3700 2700);
FORCEPROP 2 LAST PATH I81
J 0
(-3775 2875);
DISPLAY 0.680851 (-3775 2875);
DISPLAY INVISIBLE (-3775 2875);
FORCEADD OFFPAGE..3
R 2
(-3825 2750);
FORCEPROP 2 LAST $XR3 251 
J 0
(-4105 2678);
DISPLAY 0.638298 (-4105 2678);
PAINT MONO (-4105 2678);
FORCEPROP 2 LAST $XR2 179 
J 0
(-4105 2786);
DISPLAY 0.638298 (-4105 2786);
PAINT MONO (-4105 2786);
FORCEPROP 2 LAST $XR1 178 
J 0
(-4105 2714);
DISPLAY 0.638298 (-4105 2714);
PAINT MONO (-4105 2714);
FORCEPROP 2 LAST $XR0 176 
J 0
(-4105 2750);
DISPLAY 0.638298 (-4105 2750);
PAINT MONO (-4105 2750);
FORCEPROP 2 LAST CDS_LIB standard
J 0
(-3825 2750);
DISPLAY INVISIBLE (-3825 2750);
FORCEPROP 1 LAST OFFPAGE TRUE
J 2
(-4150 2625);
DISPLAY 0.872340 (-4150 2625);
PAINT GREEN (-4150 2625);
DISPLAY INVISIBLE (-4150 2625);
FORCEPROP 1 LAST COMMENT_BODY TRUE
J 2
(-3775 2650);
DISPLAY 0.872340 (-3775 2650);
PAINT GREEN (-3775 2650);
DISPLAY INVISIBLE (-3775 2650);
FORCEPROP 2 LAST PATH I82
J 0
(-3775 2825);
DISPLAY 0.680851 (-3775 2825);
DISPLAY INVISIBLE (-3775 2825);
FORCEADD Q_RES..1
(-3200 2750);
FORCEPROP 1 LAST LOCATION R6225
J 0
(-3150 2725);
DISPLAY 0.510638 (-3150 2725);
FORCEPROP 0 LAST $SEC 1
J 0
(-3150 2750);
DISPLAY 0.680851 (-3150 2750);
PAINT MONO (-3150 2750);
DISPLAY INVISIBLE (-3150 2750);
FORCEPROP 0 LAST CDS_SEC 1
J 0
(-3150 2750);
DISPLAY 0.680851 (-3150 2750);
DISPLAY INVISIBLE (-3150 2750);
FORCEPROP 1 LASTPIN (-3300 2750) $PN 1
J 0
(-3288 2762);
DISPLAY 0.787234 (-3288 2762);
PAINT MONO (-3288 2762);
FORCEPROP 1 LASTPIN (-3100 2750) $PN 2
J 0
(-3138 2762);
DISPLAY 0.787234 (-3138 2762);
PAINT MONO (-3138 2762);
FORCEPROP 2 LAST ROOM USB3_HUB1_CYP
J 0
(-3325 2675);
DISPLAY 0.446809 (-3325 2675);
PAINT RED (-3325 2675);
FORCEPROP 1 LAST MATERIAL EMPTY
J 0
(-3100 2700);
DISPLAY 0.510638 (-3100 2700);
FORCEPROP 1 LAST VALUE 33.2
J 2
(-3250 2700);
DISPLAY 0.510638 (-3250 2700);
FORCEPROP 1 LAST TOLERANCE 1%
J 0
(-3225 2700);
DISPLAY 0.510638 (-3225 2700);
FORCEPROP 2 LAST CDS_LIB pure_quanta
J 0
(-3200 2750);
DISPLAY INVISIBLE (-3200 2750);
FORCEPROP 1 LAST WATTAGE 1/16W
J 2
(-3225 2600);
DISPLAY 0.978723 (-3225 2600);
DISPLAY INVISIBLE (-3225 2600);
FORCEPROP 1 LAST PACK_TYPE 0402LF
J 0
(-2950 2600);
DISPLAY 0.978723 (-2950 2600);
DISPLAY INVISIBLE (-2950 2600);
FORCEPROP 1 LAST PATH I83
J 0
(-3250 2900);
DISPLAY 0.978723 (-3250 2900);
PAINT WHITE (-3250 2900);
DISPLAY INVISIBLE (-3250 2900);
FORCEPROP 1 LAST PART_NUMBER CS03322FB03
J 0
(-3250 2850);
DISPLAY 0.978723 (-3250 2850);
DISPLAY INVISIBLE (-3250 2850);
FORCEADD Q_RES..1
(-3200 2800);
FORCEPROP 1 LAST LOCATION R6224
J 0
(-3150 2800);
DISPLAY 0.510638 (-3150 2800);
FORCEPROP 0 LAST $SEC 1
J 0
(-3125 2875);
DISPLAY 0.680851 (-3125 2875);
PAINT MONO (-3125 2875);
DISPLAY INVISIBLE (-3125 2875);
FORCEPROP 0 LAST CDS_SEC 1
J 0
(-3125 2875);
DISPLAY 0.680851 (-3125 2875);
DISPLAY INVISIBLE (-3125 2875);
FORCEPROP 1 LASTPIN (-3300 2800) $PN 1
J 0
(-3288 2812);
DISPLAY 0.787234 (-3288 2812);
PAINT MONO (-3288 2812);
FORCEPROP 1 LASTPIN (-3100 2800) $PN 2
J 0
(-3138 2812);
DISPLAY 0.787234 (-3138 2812);
PAINT MONO (-3138 2812);
FORCEPROP 1 LAST TOLERANCE 1%
J 0
(-3225 2850);
DISPLAY 0.510638 (-3225 2850);
FORCEPROP 2 LAST ROOM USB3_HUB1_CYP
J 0
(-3325 2875);
DISPLAY 0.446809 (-3325 2875);
PAINT RED (-3325 2875);
FORCEPROP 1 LAST MATERIAL EMPTY
J 0
(-3125 2850);
DISPLAY 0.510638 (-3125 2850);
FORCEPROP 1 LAST VALUE 33.2
J 2
(-3250 2850);
DISPLAY 0.510638 (-3250 2850);
FORCEPROP 1 LAST WATTAGE 1/16W
J 2
(-3225 2650);
DISPLAY 0.978723 (-3225 2650);
DISPLAY INVISIBLE (-3225 2650);
FORCEPROP 1 LAST PACK_TYPE 0402LF
J 0
(-2950 2650);
DISPLAY 0.978723 (-2950 2650);
DISPLAY INVISIBLE (-2950 2650);
FORCEPROP 2 LAST CDS_LIB pure_quanta
J 0
(-3200 2800);
DISPLAY INVISIBLE (-3200 2800);
FORCEPROP 1 LAST PATH I84
J 0
(-3250 2950);
DISPLAY 0.978723 (-3250 2950);
PAINT WHITE (-3250 2950);
DISPLAY INVISIBLE (-3250 2950);
FORCEPROP 1 LAST PART_NUMBER CS03322FB03
J 0
(-3250 2900);
DISPLAY 0.978723 (-3250 2900);
DISPLAY INVISIBLE (-3250 2900);
FORCEADD Q_RES..2
(-2900 3300);
FORCEPROP 1 LAST LOCATION R6226
J 0
(-2855 3425);
DISPLAY 0.510638 (-2855 3425);
FORCEPROP 2 LAST SEC 1
J 0
(-2850 3525);
DISPLAY 0.680851 (-2850 3525);
PAINT MONO (-2850 3525);
DISPLAY INVISIBLE (-2850 3525);
FORCEPROP 1 LASTPIN (-2900 3400) $PN 1
J 0
(-2895 3362);
DISPLAY 0.787234 (-2895 3362);
PAINT MONO (-2895 3362);
FORCEPROP 1 LASTPIN (-2900 3200) $PN 2
J 0
(-2895 3210);
DISPLAY 0.787234 (-2895 3210);
PAINT MONO (-2895 3210);
FORCEPROP 1 LAST PACK_TYPE 0402LF
J 0
(-2850 3175);
DISPLAY 0.510638 (-2850 3175);
FORCEPROP 2 LAST ROOM USB3_HUB1_CYP
J 0
(-2875 3150);
DISPLAY 0.361702 (-2875 3150);
PAINT RED (-2875 3150);
FORCEPROP 1 LAST WATTAGE 1/16W
J 0
(-2860 3275);
DISPLAY 0.510638 (-2860 3275);
FORCEPROP 1 LAST MATERIAL EMPTY
J 0
(-2860 3225);
DISPLAY 0.510638 (-2860 3225);
FORCEPROP 1 LAST TOLERANCE 1%
J 0
(-2855 3325);
DISPLAY 0.510638 (-2855 3325);
FORCEPROP 1 LAST VALUE 10K
J 0
(-2855 3375);
DISPLAY 0.510638 (-2855 3375);
FORCEPROP 2 LAST SEC_TYPE 0402LF
J 0
(-2850 3525);
DISPLAY 0.680851 (-2850 3525);
DISPLAY INVISIBLE (-2850 3525);
FORCEPROP 2 LAST CDS_LIB pure_quanta
J 0
(-2900 3300);
DISPLAY INVISIBLE (-2900 3300);
FORCEPROP 1 LAST PATH I85
J 0
(-2850 3475);
DISPLAY 0.978723 (-2850 3475);
PAINT WHITE (-2850 3475);
DISPLAY INVISIBLE (-2850 3475);
FORCEPROP 1 LAST PART_NUMBER CS31002FB08
J 0
(-2860 3175);
DISPLAY 0.638298 (-2860 3175);
DISPLAY INVISIBLE (-2860 3175);
FORCEADD Q_RES..2
R 2
(-2975 3300);
FORCEPROP 1 LAST LOCATION R6227
J 2
(-3020 3425);
DISPLAY 0.510638 (-3020 3425);
FORCEPROP 2 LAST SEC 1
J 0
(-3025 3525);
DISPLAY 0.680851 (-3025 3525);
PAINT MONO (-3025 3525);
DISPLAY INVISIBLE (-3025 3525);
FORCEPROP 1 LASTPIN (-2975 3400) $PN 1
J 2
(-2980 3362);
DISPLAY 0.787234 (-2980 3362);
PAINT MONO (-2980 3362);
FORCEPROP 1 LASTPIN (-2975 3200) $PN 2
J 2
(-2980 3210);
DISPLAY 0.787234 (-2980 3210);
PAINT MONO (-2980 3210);
FORCEPROP 1 LAST VALUE 10K
J 2
(-3020 3375);
DISPLAY 0.510638 (-3020 3375);
FORCEPROP 1 LAST TOLERANCE 1%
J 2
(-3020 3325);
DISPLAY 0.510638 (-3020 3325);
FORCEPROP 1 LAST WATTAGE 1/16W
J 2
(-3015 3275);
DISPLAY 0.510638 (-3015 3275);
FORCEPROP 1 LAST MATERIAL EMPTY
J 2
(-3015 3225);
DISPLAY 0.510638 (-3015 3225);
FORCEPROP 2 LAST ROOM USB3_HUB1_CYP
J 0
(-3275 3150);
DISPLAY 0.446809 (-3275 3150);
PAINT RED (-3275 3150);
FORCEPROP 1 LAST PACK_TYPE 0402LF
J 2
(-3025 3175);
DISPLAY 0.510638 (-3025 3175);
FORCEPROP 2 LAST CDS_LIB pure_quanta
J 2
(-2975 3300);
DISPLAY INVISIBLE (-2975 3300);
FORCEPROP 2 LAST SEC_TYPE 0402LF
J 0
(-3025 3525);
DISPLAY 0.680851 (-3025 3525);
DISPLAY INVISIBLE (-3025 3525);
FORCEPROP 1 LAST PATH I86
J 2
(-3025 3475);
DISPLAY 0.978723 (-3025 3475);
PAINT WHITE (-3025 3475);
DISPLAY INVISIBLE (-3025 3475);
FORCEPROP 1 LAST PART_NUMBER CS31002FB08
J 2
(-3015 3175);
DISPLAY 0.638298 (-3015 3175);
DISPLAY INVISIBLE (-3015 3175);
FORCEADD Q_RES..2
(-3300 1125);
FORCEPROP 1 LAST LOCATION R6213
J 0
(-3255 1250);
DISPLAY 0.808511 (-3255 1250);
FORCEPROP 0 LAST $SEC 1
J 0
(-3250 1300);
DISPLAY 0.680851 (-3250 1300);
PAINT MONO (-3250 1300);
DISPLAY INVISIBLE (-3250 1300);
FORCEPROP 0 LAST CDS_SEC 1
J 0
(-3250 1300);
DISPLAY 0.680851 (-3250 1300);
DISPLAY INVISIBLE (-3250 1300);
FORCEPROP 1 LASTPIN (-3300 1225) $PN 1
J 0
(-3295 1187);
DISPLAY 0.787234 (-3295 1187);
PAINT MONO (-3295 1187);
FORCEPROP 1 LASTPIN (-3300 1025) $PN 2
J 0
(-3295 1035);
DISPLAY 0.787234 (-3295 1035);
PAINT MONO (-3295 1035);
FORCEPROP 1 LAST PACK_TYPE 0402LF
J 0
(-3260 950);
DISPLAY 0.638298 (-3260 950);
FORCEPROP 1 LAST MATERIAL CHIP
J 0
(-3260 1050);
DISPLAY 0.638298 (-3260 1050);
FORCEPROP 1 LAST VALUE 10K
J 0
(-3255 1200);
DISPLAY 0.638298 (-3255 1200);
FORCEPROP 1 LAST TOLERANCE 1%
J 0
(-3255 1150);
DISPLAY 0.638298 (-3255 1150);
FORCEPROP 1 LAST WATTAGE 1/16W
J 0
(-3260 1100);
DISPLAY 0.638298 (-3260 1100);
FORCEPROP 2 LAST ROOM USB3_HUB1_CYP
J 0
(-3250 1300);
DISPLAY 0.553191 (-3250 1300);
PAINT RED (-3250 1300);
FORCEPROP 2 LAST CDS_LIB pure_quanta
J 0
(-3300 1125);
DISPLAY INVISIBLE (-3300 1125);
FORCEPROP 1 LAST PATH I87
J 0
(-3250 1300);
DISPLAY 0.978723 (-3250 1300);
PAINT WHITE (-3250 1300);
DISPLAY INVISIBLE (-3250 1300);
FORCEPROP 1 LAST PART_NUMBER CS31002FB08
J 0
(-3260 1000);
DISPLAY 0.638298 (-3260 1000);
DISPLAY INVISIBLE (-3260 1000);
FORCEADD Q_RES..2
(-3300 750);
FORCEPROP 1 LAST LOCATION R6214
J 0
(-3255 875);
DISPLAY 0.638298 (-3255 875);
FORCEPROP 0 LAST $SEC 1
J 0
(-3250 925);
DISPLAY 0.680851 (-3250 925);
PAINT MONO (-3250 925);
DISPLAY INVISIBLE (-3250 925);
FORCEPROP 0 LAST CDS_SEC 1
J 0
(-3250 925);
DISPLAY 0.680851 (-3250 925);
DISPLAY INVISIBLE (-3250 925);
FORCEPROP 1 LASTPIN (-3300 850) $PN 1
J 0
(-3295 812);
DISPLAY 0.787234 (-3295 812);
PAINT MONO (-3295 812);
FORCEPROP 1 LASTPIN (-3300 650) $PN 2
J 0
(-3295 660);
DISPLAY 0.787234 (-3295 660);
PAINT MONO (-3295 660);
FORCEPROP 2 LAST ROOM USB3_HUB1_CYP
J 0
(-3250 525);
DISPLAY 0.553191 (-3250 525);
PAINT RED (-3250 525);
FORCEPROP 1 LAST WATTAGE 1/16W
J 0
(-3260 725);
DISPLAY 0.638298 (-3260 725);
FORCEPROP 1 LAST MATERIAL EMPTY
J 0
(-3260 675);
DISPLAY 0.638298 (-3260 675);
FORCEPROP 1 LAST VALUE 10K
J 0
(-3255 825);
DISPLAY 0.638298 (-3255 825);
FORCEPROP 1 LAST PACK_TYPE 0402LF
J 0
(-3260 575);
DISPLAY 0.638298 (-3260 575);
FORCEPROP 1 LAST TOLERANCE 1%
J 0
(-3255 775);
DISPLAY 0.638298 (-3255 775);
FORCEPROP 2 LAST CDS_LIB pure_quanta
J 0
(-3300 750);
DISPLAY INVISIBLE (-3300 750);
FORCEPROP 1 LAST PATH I88
J 0
(-3250 925);
DISPLAY 0.978723 (-3250 925);
PAINT WHITE (-3250 925);
DISPLAY INVISIBLE (-3250 925);
FORCEPROP 1 LAST PART_NUMBER CS31002FB08
J 0
(-3260 625);
DISPLAY 0.638298 (-3260 625);
DISPLAY INVISIBLE (-3260 625);
FORCEADD Q_RES..2
(-2850 1125);
FORCEPROP 1 LAST LOCATION R6215
J 0
(-2805 1250);
DISPLAY 0.808511 (-2805 1250);
FORCEPROP 0 LAST $SEC 1
J 0
(-2800 1300);
DISPLAY 0.680851 (-2800 1300);
PAINT MONO (-2800 1300);
DISPLAY INVISIBLE (-2800 1300);
FORCEPROP 0 LAST CDS_SEC 1
J 0
(-2800 1300);
DISPLAY 0.680851 (-2800 1300);
DISPLAY INVISIBLE (-2800 1300);
FORCEPROP 1 LASTPIN (-2850 1225) $PN 1
J 0
(-2845 1187);
DISPLAY 0.787234 (-2845 1187);
PAINT MONO (-2845 1187);
FORCEPROP 1 LASTPIN (-2850 1025) $PN 2
J 0
(-2845 1035);
DISPLAY 0.787234 (-2845 1035);
PAINT MONO (-2845 1035);
FORCEPROP 1 LAST TOLERANCE 1%
J 0
(-2805 1150);
DISPLAY 0.638298 (-2805 1150);
FORCEPROP 1 LAST WATTAGE 1/16W
J 0
(-2810 1100);
DISPLAY 0.638298 (-2810 1100);
FORCEPROP 1 LAST PACK_TYPE 0402LF
J 0
(-2810 950);
DISPLAY 0.638298 (-2810 950);
FORCEPROP 1 LAST MATERIAL CHIP
J 0
(-2810 1050);
DISPLAY 0.638298 (-2810 1050);
FORCEPROP 1 LAST VALUE 10K
J 0
(-2805 1200);
DISPLAY 0.638298 (-2805 1200);
FORCEPROP 2 LAST ROOM USB3_HUB1_CYP
J 0
(-2800 1300);
DISPLAY 0.553191 (-2800 1300);
PAINT RED (-2800 1300);
FORCEPROP 2 LAST CDS_LIB pure_quanta
J 0
(-2850 1125);
DISPLAY INVISIBLE (-2850 1125);
FORCEPROP 1 LAST PATH I89
J 0
(-2800 1300);
DISPLAY 0.978723 (-2800 1300);
PAINT WHITE (-2800 1300);
DISPLAY INVISIBLE (-2800 1300);
FORCEPROP 1 LAST PART_NUMBER CS31002FB08
J 0
(-2810 1000);
DISPLAY 0.638298 (-2810 1000);
DISPLAY INVISIBLE (-2810 1000);
FORCEADD OFFPAGE..3
(-3025 5725);
FORCEPROP 2 LAST $XR0 180 
J 0
(-2811 5725);
DISPLAY 0.638298 (-2811 5725);
PAINT MONO (-2811 5725);
FORCEPROP 2 LAST CDS_LIB standard
J 0
(-3025 5725);
DISPLAY INVISIBLE (-3025 5725);
FORCEPROP 1 LAST OFFPAGE TRUE
J 0
(-2700 5600);
DISPLAY 0.872340 (-2700 5600);
PAINT GREEN (-2700 5600);
DISPLAY INVISIBLE (-2700 5600);
FORCEPROP 1 LAST COMMENT_BODY TRUE
J 0
(-3075 5625);
DISPLAY 0.872340 (-3075 5625);
PAINT GREEN (-3075 5625);
DISPLAY INVISIBLE (-3075 5625);
FORCEPROP 2 LAST PATH I9
J 0
(-2825 5800);
DISPLAY 0.680851 (-2825 5800);
DISPLAY INVISIBLE (-2825 5800);
FORCEADD Q_RES..2
(-2850 725);
FORCEPROP 1 LAST LOCATION R6216
J 0
(-2805 850);
DISPLAY 0.638298 (-2805 850);
FORCEPROP 0 LAST $SEC 1
J 0
(-2800 900);
DISPLAY 0.680851 (-2800 900);
PAINT MONO (-2800 900);
DISPLAY INVISIBLE (-2800 900);
FORCEPROP 0 LAST CDS_SEC 1
J 0
(-2800 900);
DISPLAY 0.680851 (-2800 900);
DISPLAY INVISIBLE (-2800 900);
FORCEPROP 1 LASTPIN (-2850 825) $PN 1
J 0
(-2845 787);
DISPLAY 0.787234 (-2845 787);
PAINT MONO (-2845 787);
FORCEPROP 1 LASTPIN (-2850 625) $PN 2
J 0
(-2845 635);
DISPLAY 0.787234 (-2845 635);
PAINT MONO (-2845 635);
FORCEPROP 2 LAST ROOM USB3_HUB1_CYP
J 0
(-2800 500);
DISPLAY 0.553191 (-2800 500);
PAINT RED (-2800 500);
FORCEPROP 1 LAST VALUE 10K
J 0
(-2805 800);
DISPLAY 0.638298 (-2805 800);
FORCEPROP 1 LAST MATERIAL EMPTY
J 0
(-2810 650);
DISPLAY 0.638298 (-2810 650);
FORCEPROP 1 LAST PACK_TYPE 0402LF
J 0
(-2810 550);
DISPLAY 0.638298 (-2810 550);
FORCEPROP 1 LAST WATTAGE 1/16W
J 0
(-2810 700);
DISPLAY 0.638298 (-2810 700);
FORCEPROP 1 LAST TOLERANCE 1%
J 0
(-2805 750);
DISPLAY 0.638298 (-2805 750);
FORCEPROP 2 LAST CDS_LIB pure_quanta
J 0
(-2850 725);
DISPLAY INVISIBLE (-2850 725);
FORCEPROP 1 LAST PATH I90
J 0
(-2800 900);
DISPLAY 0.978723 (-2800 900);
PAINT WHITE (-2800 900);
DISPLAY INVISIBLE (-2800 900);
FORCEPROP 1 LAST PART_NUMBER CS31002FB08
J 0
(-2810 600);
DISPLAY 0.638298 (-2810 600);
DISPLAY INVISIBLE (-2810 600);
FORCEADD Q_CAP..1
(-8000 1550);
FORCEPROP 1 LAST LOCATION C93
J 0
(-7950 1650);
DISPLAY 0.808511 (-7950 1650);
FORCEPROP 0 LAST $SEC 1
J 0
(-7950 1700);
DISPLAY 0.680851 (-7950 1700);
PAINT MONO (-7950 1700);
DISPLAY INVISIBLE (-7950 1700);
FORCEPROP 0 LAST CDS_SEC 1
J 0
(-7950 1700);
DISPLAY 0.680851 (-7950 1700);
DISPLAY INVISIBLE (-7950 1700);
FORCEPROP 1 LASTPIN (-8000 1650) $PN 1
J 0
(-7990 1630);
DISPLAY 0.787234 (-7990 1630);
PAINT MONO (-7990 1630);
FORCEPROP 1 LASTPIN (-8000 1450) $PN 2
J 0
(-7990 1430);
DISPLAY 0.787234 (-7990 1430);
PAINT MONO (-7990 1430);
FORCEPROP 1 LAST VOLTAGE 50V
J 0
(-7950 1550);
DISPLAY 0.638298 (-7950 1550);
FORCEPROP 1 LAST MATERIAL C0G
J 0
(-7950 1450);
DISPLAY 0.638298 (-7950 1450);
FORCEPROP 1 LAST TOLERANCE 5%
J 0
(-7950 1500);
DISPLAY 0.638298 (-7950 1500);
FORCEPROP 1 LAST PACK_TYPE 0402
J 0
(-7950 1350);
DISPLAY 0.638298 (-7950 1350);
FORCEPROP 1 LAST VALUE 15PF
J 0
(-7950 1600);
DISPLAY 0.638298 (-7950 1600);
FORCEPROP 2 LAST ROOM USB3_HUB1_CYP
J 0
(-7950 1700);
DISPLAY 0.680851 (-7950 1700);
PAINT RED (-7950 1700);
FORCEPROP 2 LAST CDS_LIB pure_quanta
J 0
(-8000 1550);
DISPLAY INVISIBLE (-8000 1550);
FORCEPROP 1 LAST PATH I91
J 0
(-7950 1700);
DISPLAY 0.978723 (-7950 1700);
PAINT WHITE (-7950 1700);
DISPLAY INVISIBLE (-7950 1700);
FORCEPROP 1 LAST PART_NUMBER CH01506JB06
J 0
(-7950 1400);
DISPLAY 0.638298 (-7950 1400);
DISPLAY INVISIBLE (-7950 1400);
FORCEADD Q_CAP..1
(-6350 1500);
FORCEPROP 1 LAST LOCATION C91
J 0
(-6300 1600);
DISPLAY 0.808511 (-6300 1600);
FORCEPROP 0 LAST $SEC 1
J 0
(-6300 1650);
DISPLAY 0.680851 (-6300 1650);
PAINT MONO (-6300 1650);
DISPLAY INVISIBLE (-6300 1650);
FORCEPROP 0 LAST CDS_SEC 1
J 0
(-6300 1650);
DISPLAY 0.680851 (-6300 1650);
DISPLAY INVISIBLE (-6300 1650);
FORCEPROP 1 LASTPIN (-6350 1600) $PN 1
J 0
(-6340 1580);
DISPLAY 0.787234 (-6340 1580);
PAINT MONO (-6340 1580);
FORCEPROP 1 LASTPIN (-6350 1400) $PN 2
J 0
(-6340 1380);
DISPLAY 0.787234 (-6340 1380);
PAINT MONO (-6340 1380);
FORCEPROP 1 LAST TOLERANCE 5%
J 0
(-6300 1450);
DISPLAY 0.638298 (-6300 1450);
FORCEPROP 1 LAST MATERIAL C0G
J 0
(-6300 1400);
DISPLAY 0.638298 (-6300 1400);
FORCEPROP 1 LAST VOLTAGE 50V
J 0
(-6300 1500);
DISPLAY 0.638298 (-6300 1500);
FORCEPROP 1 LAST VALUE 12PF
J 0
(-6300 1550);
DISPLAY 0.638298 (-6300 1550);
FORCEPROP 2 LAST ROOM USB3_HUB1_CYP
J 0
(-6300 1650);
DISPLAY 0.680851 (-6300 1650);
PAINT RED (-6300 1650);
FORCEPROP 1 LAST PACK_TYPE C0402
J 0
(-6300 1300);
DISPLAY 0.638298 (-6300 1300);
FORCEPROP 2 LAST CDS_LIB pure_quanta
J 0
(-6350 1500);
DISPLAY INVISIBLE (-6350 1500);
FORCEPROP 1 LAST PATH I92
J 0
(-6300 1650);
DISPLAY 0.978723 (-6300 1650);
PAINT WHITE (-6300 1650);
DISPLAY INVISIBLE (-6300 1650);
FORCEPROP 1 LAST PART_NUMBER CH01206JB05
J 0
(-6300 1350);
DISPLAY 0.638298 (-6300 1350);
DISPLAY INVISIBLE (-6300 1350);
FORCEADD Q_RES..2
(-6875 850);
FORCEPROP 1 LAST LOCATION R4452
J 0
(-6830 975);
DISPLAY 0.638298 (-6830 975);
FORCEPROP 0 LAST $SEC 1
J 0
(-6825 1025);
DISPLAY 0.680851 (-6825 1025);
PAINT MONO (-6825 1025);
DISPLAY INVISIBLE (-6825 1025);
FORCEPROP 0 LAST CDS_SEC 1
J 0
(-6825 1025);
DISPLAY 0.680851 (-6825 1025);
DISPLAY INVISIBLE (-6825 1025);
FORCEPROP 1 LASTPIN (-6875 950) $PN 1
J 0
(-6870 912);
DISPLAY 0.787234 (-6870 912);
PAINT MONO (-6870 912);
FORCEPROP 1 LASTPIN (-6875 750) $PN 2
J 0
(-6870 760);
DISPLAY 0.787234 (-6870 760);
PAINT MONO (-6870 760);
FORCEPROP 1 LAST PACK_TYPE 0402LF
J 0
(-6835 675);
DISPLAY 0.638298 (-6835 675);
FORCEPROP 1 LAST TOLERANCE 1%
J 0
(-6830 875);
DISPLAY 0.638298 (-6830 875);
FORCEPROP 1 LAST VALUE 10K
J 0
(-6830 925);
DISPLAY 0.638298 (-6830 925);
FORCEPROP 1 LAST MATERIAL EMPTY
J 0
(-6835 775);
DISPLAY 0.638298 (-6835 775);
PAINT RED (-6835 775);
FORCEPROP 1 LAST WATTAGE 1/16W
J 0
(-6835 825);
DISPLAY 0.638298 (-6835 825);
FORCEPROP 2 LAST ROOM USB3_HUB1_CYP
J 0
(-6825 1025);
DISPLAY 0.553191 (-6825 1025);
PAINT RED (-6825 1025);
FORCEPROP 2 LAST CDS_LIB pure_quanta
J 0
(-6875 850);
DISPLAY INVISIBLE (-6875 850);
FORCEPROP 1 LAST PATH I93
J 0
(-6825 1025);
DISPLAY 0.978723 (-6825 1025);
PAINT WHITE (-6825 1025);
DISPLAY INVISIBLE (-6825 1025);
FORCEPROP 1 LAST PART_NUMBER CS31002FB08
J 0
(-6835 725);
DISPLAY 0.638298 (-6835 725);
DISPLAY INVISIBLE (-6835 725);
FORCEADD DNS..1
(-6750 850);
PAINT RED (-6750 850);
FORCEPROP 2 LAST BOM_COST VR_SYSTEM 
J 0
(-6925 1025);
DISPLAY 0.680851 (-6925 1025);
DISPLAY INVISIBLE (-6925 1025);
FORCEPROP 2 LAST CDS_LIB mstr_misc
J 0
(-6750 850);
DISPLAY INVISIBLE (-6750 850);
FORCEPROP 1 LAST COMMENT_BODY TRUE
J 0
(-6750 850);
DISPLAY INVISIBLE (-6750 850);
FORCEADD DNS..1
(-5850 375);
PAINT RED (-5850 375);
FORCEPROP 2 LAST CDS_LIB mstr_misc
J 0
(-5850 375);
DISPLAY INVISIBLE (-5850 375);
FORCEPROP 2 LAST BOM_COST VR_SYSTEM 
J 0
(-6025 550);
DISPLAY 0.680851 (-6025 550);
DISPLAY INVISIBLE (-6025 550);
FORCEPROP 1 LAST COMMENT_BODY TRUE
J 0
(-5850 375);
DISPLAY INVISIBLE (-5850 375);
FORCEADD DNS..1
(-1050 2375);
PAINT RED (-1050 2375);
FORCEPROP 2 LAST CDS_LIB mstr_misc
J 0
(-1050 2375);
DISPLAY INVISIBLE (-1050 2375);
FORCEPROP 2 LAST BOM_COST VR_SYSTEM 
J 0
(-1225 2550);
DISPLAY 0.680851 (-1225 2550);
DISPLAY INVISIBLE (-1225 2550);
FORCEPROP 1 LAST COMMENT_BODY TRUE
J 0
(-1050 2375);
DISPLAY INVISIBLE (-1050 2375);
FORCEADD DNS..1
(-3200 2700);
PAINT RED (-3200 2700);
FORCEPROP 2 LAST CDS_LIB mstr_misc
J 0
(-3200 2700);
DISPLAY INVISIBLE (-3200 2700);
FORCEPROP 2 LAST BOM_COST VR_SYSTEM 
J 0
(-3375 2875);
DISPLAY 0.680851 (-3375 2875);
DISPLAY INVISIBLE (-3375 2875);
FORCEPROP 1 LAST COMMENT_BODY TRUE
J 0
(-3200 2700);
DISPLAY INVISIBLE (-3200 2700);
FORCEADD DNS..1
(-2800 725);
PAINT RED (-2800 725);
FORCEPROP 2 LAST CDS_LIB mstr_misc
J 0
(-2800 725);
DISPLAY INVISIBLE (-2800 725);
FORCEPROP 2 LAST BOM_COST VR_SYSTEM 
J 0
(-2975 900);
DISPLAY 0.680851 (-2975 900);
DISPLAY INVISIBLE (-2975 900);
FORCEPROP 1 LAST COMMENT_BODY TRUE
J 0
(-2800 725);
DISPLAY INVISIBLE (-2800 725);
FORCEADD QUANTA_TITLE_BLOCK_C..1
(0 0);
FORCEPROP 0 LAST CDS_CON_LAST_MODIFIED Thu Sep 14 16:12:46 2023
J 0
(-1885 15);
DISPLAY INVISIBLE (-1885 15);
FORCEPROP 1 LAST CUSTOM_TXT_CDS <CON_LAST_MODIFIED>
J 0
(-1885 15);
DISPLAY 0.978723 (-1885 15);
FORCEPROP 2 LAST CUSTOM_TXT_CDS <XR_PAGE_TITLE>
J 0
(-7890 5250);
DISPLAY 0.638298 (-7890 5250);
PAINT PINK (-7890 5250);
DISPLAY INVISIBLE (-7890 5250);
FORCEPROP 1 LAST CUSTOM_TXT_CDS <NAME_2>
J 0
(-3175 50);
FORCEPROP 1 LAST CUSTOM_TXT_CDS <NAME_1>
J 0
(-3175 175);
FORCEPROP 1 LAST CUSTOM_TXT_CDS <Q_NUMBER>
J 0
(-1403 103);
DISPLAY 1.212766 (-1403 103);
FORCEPROP 1 LAST CUSTOM_TXT_CDS <Q_PROJ>
J 0
(-2382 102);
DISPLAY 1.212766 (-2382 102);
FORCEPROP 1 LAST CUSTOM_TXT_CDS <Q_REV>
J 0
(-184 103);
DISPLAY 1.212766 (-184 103);
FORCEPROP 1 LAST CUSTOM_TXT_CDS <CON_PAGE_NUM> OF <CON_TOTAL_PAGES>
J 0
(-446 18);
DISPLAY 0.978723 (-446 18);
FORCEPROP 1 LAST Q_TITLE USB3.0 EXT HUB MAIN(1/2)
J 0
(-9250 75);
DISPLAY 2.446809 (-9250 75);
PAINT GREEN (-9250 75);
FORCEPROP 1 LAST CDS_LMAN_SYM_OUTLINE -9475,6775,100,-125
J 0
(0 0);
DISPLAY 0.468085 (0 0);
PAINT GREEN (0 0);
DISPLAY INVISIBLE (0 0);
FORCEPROP 2 LAST CDS_LIB pure_quanta
J 0
(0 0);
DISPLAY INVISIBLE (0 0);
FORCEPROP 2 LAST PAGE_BORDER TRUE
J 0
(-7890 5250);
DISPLAY 0.638298 (-7890 5250);
PAINT PINK (-7890 5250);
DISPLAY INVISIBLE (-7890 5250);
FORCEPROP 2 LAST CDS_XR_PAGE_TITLE CR-176 : @T6G_MB_LIB.T6G(SCH_1):PAGE176
J 0
(-7890 5250);
DISPLAY 0.638298 (-7890 5250);
PAINT PINK (-7890 5250);
DISPLAY INVISIBLE (-7890 5250);
FORCEPROP 1 LAST Q_DEPT BU9
J 1
(-3763 49);
DISPLAY 1.957447 (-3763 49);
PAINT GREEN (-3763 49);
DISPLAY INVISIBLE (-3763 49);
FORCEPROP 1 LAST COMMENT_BODY TRUE
J 0
(12 -13);
DISPLAY 0.978723 (12 -13);
PAINT GREEN (12 -13);
DISPLAY INVISIBLE (12 -13);
FORCEADD DNS..1
(-3075 3300);
PAINT RED (-3075 3300);
FORCEPROP 2 LAST CDS_LIB mstr_misc
J 0
(-3075 3300);
DISPLAY INVISIBLE (-3075 3300);
FORCEPROP 2 LAST BOM_COST VR_SYSTEM 
J 0
(-3250 3475);
DISPLAY 0.680851 (-3250 3475);
DISPLAY INVISIBLE (-3250 3475);
FORCEPROP 1 LAST COMMENT_BODY TRUE
J 0
(-3075 3300);
DISPLAY INVISIBLE (-3075 3300);
FORCEADD DNS..1
(-775 3225);
PAINT RED (-775 3225);
FORCEPROP 2 LAST BOM_COST VR_SYSTEM 
J 0
(-950 3400);
DISPLAY 0.680851 (-950 3400);
DISPLAY INVISIBLE (-950 3400);
FORCEPROP 2 LAST CDS_LIB mstr_misc
J 0
(-775 3225);
DISPLAY INVISIBLE (-775 3225);
FORCEPROP 1 LAST COMMENT_BODY TRUE
J 0
(-775 3225);
DISPLAY INVISIBLE (-775 3225);
FORCEADD DNS..1
(-2875 3300);
PAINT RED (-2875 3300);
FORCEPROP 2 LAST CDS_LIB mstr_misc
J 0
(-2875 3300);
DISPLAY INVISIBLE (-2875 3300);
FORCEPROP 2 LAST BOM_COST VR_SYSTEM 
J 0
(-3050 3475);
DISPLAY 0.680851 (-3050 3475);
DISPLAY INVISIBLE (-3050 3475);
FORCEPROP 1 LAST COMMENT_BODY TRUE
J 0
(-2875 3300);
DISPLAY INVISIBLE (-2875 3300);
FORCEADD DNS..1
(-350 3200);
PAINT RED (-350 3200);
FORCEPROP 2 LAST BOM_COST VR_SYSTEM 
J 0
(-525 3375);
DISPLAY 0.680851 (-525 3375);
DISPLAY INVISIBLE (-525 3375);
FORCEPROP 2 LAST CDS_LIB mstr_misc
J 0
(-350 3200);
DISPLAY INVISIBLE (-350 3200);
FORCEPROP 1 LAST COMMENT_BODY TRUE
J 0
(-350 3200);
DISPLAY INVISIBLE (-350 3200);
FORCEADD DNS..1
(-3325 725);
PAINT RED (-3325 725);
FORCEPROP 2 LAST CDS_LIB mstr_misc
J 0
(-3325 725);
DISPLAY INVISIBLE (-3325 725);
FORCEPROP 2 LAST BOM_COST VR_SYSTEM 
J 0
(-3500 900);
DISPLAY 0.680851 (-3500 900);
DISPLAY INVISIBLE (-3500 900);
FORCEPROP 1 LAST COMMENT_BODY TRUE
J 0
(-3325 725);
DISPLAY INVISIBLE (-3325 725);
FORCEADD DNS..1
(-3175 2825);
PAINT RED (-3175 2825);
FORCEPROP 2 LAST BOM_COST VR_SYSTEM 
J 0
(-3350 3000);
DISPLAY 0.680851 (-3350 3000);
DISPLAY INVISIBLE (-3350 3000);
FORCEPROP 2 LAST CDS_LIB mstr_misc
J 0
(-3175 2825);
DISPLAY INVISIBLE (-3175 2825);
FORCEPROP 1 LAST COMMENT_BODY TRUE
J 0
(-3175 2825);
DISPLAY INVISIBLE (-3175 2825);
WIRE 16 -1 (-6875 950)(-6875 1100);
WIRE 16 -1 (-2475 6125)(-2475 6375);
WIRE 16 -1 (-2475 6125)(-2725 6125);
WIRE 16 -1 (-7025 6475)(-7025 6400);
WIRE 16 -1 (-7025 5700)(-7025 5425);
WIRE 16 -1 (-3300 650)(-3300 550);
WIRE 16 -1 (-2850 625)(-2850 525);
WIRE 16 -1 (-1750 2750)(-1550 2750);
WIRE 16 -1 (-1550 2750)(-1550 2675);
WIRE 16 -1 (-2650 3225)(-2650 3125);
WIRE 16 -1 (-2700 2325)(-2700 2175);
WIRE 16 -1 (-5275 2775)(-7775 2775);
FORCEPROP 2 LAST SIG_NAME PU_CPU0_USB_HUB_RESERVED2
J 0
(-6410 2785);
DISPLAY 0.680851 (-6410 2785);
FORCEPROP 2 LASTPROP $XRERR UNIQUE?
J 0
(-6650 2785);
DISPLAY 0.638298 (-6650 2785);
PAINT MONO (-6650 2785);
DISPLAY INVISIBLE (-6650 2785);
WIRE 16 -1 (-7775 2775)(-7775 3175);
WIRE 16 -1 (-3300 2750)(-3775 2750);
FORCEPROP 2 LAST SIG_NAME SMB_USB_CPU0_HUB1_SDA
J 0
(-3760 2760);
DISPLAY 0.446809 (-3760 2760);
WIRE 16 -1 (-6350 1750)(-6350 2125);
FORCEPROP 2 LAST SIG_NAME XTAL_USB_CPU0_HUB1_XIN
J 0
(-6310 2160);
DISPLAY 0.680851 (-6310 2160);
FORCEPROP 2 LASTPROP $XRERR UNIQUE?
J 0
(-6550 2160);
DISPLAY 0.638298 (-6550 2160);
PAINT MONO (-6550 2160);
DISPLAY INVISIBLE (-6550 2160);
WIRE 16 -1 (-6350 1750)(-6350 1600);
WIRE 16 -1 (-6350 1750)(-6725 1750);
WIRE 16 -1 (-6350 2125)(-5275 2125);
WIRE 16 -1 (-6725 1550)(-6725 1225);
WIRE 16 -1 (-6725 1225)(-6350 1225);
WIRE 16 -1 (-6350 1400)(-6350 1225);
WIRE 16 -1 (-6350 1225)(-6350 1050);
WIRE 16 -1 (-7350 600)(-6875 600);
WIRE 16 -1 (-6875 600)(-6350 600);
WIRE 16 -1 (-6875 600)(-6875 750);
WIRE 16 -1 (-6350 600)(-5875 600);
WIRE 16 -1 (-6350 525)(-6350 600);
WIRE 16 -1 (-5875 600)(-5750 600);
WIRE 16 -1 (-5875 475)(-5875 600);
WIRE 16 -1 (-5750 600)(-5750 1825);
FORCEPROP 2 LAST SIG_NAME RST_USB_CPU0_HUB1_R_N
J 0
(-6035 1860);
DISPLAY 0.680851 (-6035 1860);
FORCEPROP 2 LASTPROP $XRERR UNIQUE?
J 0
(-6275 1860);
DISPLAY 0.638298 (-6275 1860);
PAINT MONO (-6275 1860);
DISPLAY INVISIBLE (-6275 1860);
WIRE 16 -1 (-5750 1825)(-5275 1825);
WIRE 16 -1 (-5275 1575)(-5650 1575);
WIRE 16 -1 (-5650 1575)(-5650 925);
WIRE 16 -1 (-5650 925)(-2850 925);
FORCEPROP 2 LAST SIG_NAME USB_CPU0_HUB1_MODE_SEL0
J 0
(-4960 935);
DISPLAY 0.680851 (-4960 935);
FORCEPROP 2 LASTPROP $XRERR UNIQUE?
J 0
(-5200 935);
DISPLAY 0.638298 (-5200 935);
PAINT MONO (-5200 935);
DISPLAY INVISIBLE (-5200 935);
WIRE 16 -1 (-2850 1025)(-2850 925);
WIRE 16 -1 (-2850 925)(-2850 825);
WIRE 16 -1 (-4025 1325)(-3800 1325);
WIRE 16 -1 (-3800 1325)(-3800 1275);
WIRE 16 -1 (-4025 1275)(-3800 1275);
WIRE 16 -1 (-3800 1275)(-3800 1125);
WIRE 16 -1 (-3300 1225)(-3300 1400);
WIRE 16 -1 (-3300 1400)(-3100 1400);
WIRE 16 -1 (-3100 1400)(-2850 1400);
WIRE 16 -1 (-3100 1400)(-3100 1475);
WIRE 16 -1 (-2850 1400)(-2850 1225);
WIRE 16 -1 (-2350 2900)(-2425 2900);
WIRE 16 -1 (-2425 2900)(-2425 3500);
WIRE 16 -1 (-2425 3500)(-2650 3500);
WIRE 16 -1 (-2425 3500)(-2425 3525);
WIRE 16 -1 (-2650 3500)(-2650 3425);
WIRE 16 -1 (-2900 3500)(-2650 3500);
WIRE 16 -1 (-2900 3400)(-2900 3500);
WIRE 16 -1 (-2975 3500)(-2900 3500);
WIRE 16 -1 (-2975 3400)(-2975 3500);
WIRE 16 -1 (-850 3650)(-450 3650);
WIRE 16 -1 (-850 3300)(-850 3650);
WIRE 16 -1 (-850 3650)(-1050 3650);
WIRE 16 -1 (-450 3650)(-450 3300);
WIRE 16 -1 (-1050 3325)(-1050 3650);
WIRE 16 -1 (-1050 3650)(-1050 3725);
WIRE 16 -1 (-450 2275)(-450 2050);
WIRE 16 -1 (-450 2050)(-850 2050);
WIRE 16 -1 (-850 2275)(-850 2050);
WIRE 16 -1 (-850 2050)(-1050 2050);
WIRE 16 -1 (-1050 2300)(-1050 2050);
WIRE 16 -1 (-1050 2050)(-1050 1975);
WIRE 16 -1 (-7650 3650)(-7775 3650);
WIRE 16 -1 (-7650 3650)(-7475 3650);
WIRE 16 -1 (-7650 3650)(-7650 3725);
WIRE 16 -1 (-7775 3650)(-8100 3650);
WIRE 16 -1 (-7775 3650)(-7775 3375);
WIRE 16 -1 (-8100 3650)(-8100 3375);
WIRE 16 -1 (-7475 3650)(-7175 3650);
WIRE 16 -1 (-7475 3650)(-7475 3375);
WIRE 16 -1 (-7175 3375)(-7175 3650);
WIRE 16 -1 (-7100 4225)(-7725 4225);
WIRE 16 -1 (-7725 4125)(-7725 4225);
WIRE 16 -1 (-7125 4125)(-7725 4125);
WIRE 16 -1 (-7725 4050)(-7725 4125);
WIRE 16 -1 (-1525 6125)(-1525 6300);
WIRE 16 -1 (-1075 6300)(-1525 6300);
WIRE 16 -1 (-1525 6350)(-1525 6300);
WIRE 16 -1 (-1075 6300)(-1075 6100);
WIRE 16 -1 (-1075 5900)(-1075 5650);
WIRE 16 -1 (-975 5650)(-1075 5650);
WIRE 16 -1 (-1525 5650)(-1075 5650);
WIRE 16 -1 (-1525 5925)(-1525 5650);
WIRE 16 -1 (-975 5650)(-975 5450);
WIRE 16 -1 (-6350 325)(-6350 200);
WIRE 16 -1 (-6350 200)(-5875 200);
WIRE 16 -1 (-5875 275)(-5875 200);
WIRE 16 -1 (-5875 200)(-5875 150);
WIRE 16 -1 (-7300 1275)(-7300 1550);
WIRE 16 -1 (-7300 1275)(-8000 1275);
WIRE 16 -1 (-7300 1550)(-7275 1550);
WIRE 16 -1 (-8000 1275)(-8000 1450);
WIRE 16 -1 (-8000 1275)(-8000 1075);
WIRE 16 -1 (-5275 1175)(-5450 1175);
WIRE 16 -1 (-5450 1175)(-5450 975);
WIRE 16 -1 (-5450 975)(-3300 975);
FORCEPROP 2 LAST SIG_NAME USB_CPU0_HUB1_MODE_SEL1
J 0
(-4960 1010);
DISPLAY 0.680851 (-4960 1010);
FORCEPROP 2 LASTPROP $XRERR UNIQUE?
J 0
(-5200 1010);
DISPLAY 0.638298 (-5200 1010);
PAINT MONO (-5200 1010);
DISPLAY INVISIBLE (-5200 1010);
WIRE 16 -1 (-3300 975)(-3300 1025);
WIRE 16 -1 (-3300 975)(-3300 850);
WIRE 16 -1 (-3075 5775)(-4025 5775);
FORCEPROP 2 LAST SIG_NAME USB2_CPU0_P0_HUB1_R_DN
J 0
(-3885 5785);
DISPLAY 0.680851 (-3885 5785);
WIRE 16 -1 (-3075 5725)(-4025 5725);
FORCEPROP 2 LAST SIG_NAME USB2_CPU0_P0_HUB1_R_DP
J 0
(-3885 5735);
DISPLAY 0.680851 (-3885 5735);
WIRE 16 -1 (-3075 5625)(-4025 5625);
FORCEPROP 2 LAST SIG_NAME USB3_CPU0_BMC_RX_C1_DN
J 0
(-3860 5635);
DISPLAY 0.680851 (-3860 5635);
WIRE 16 -1 (-3075 5575)(-4025 5575);
FORCEPROP 2 LAST SIG_NAME USB3_CPU0_BMC_RX_C1_DP
J 0
(-3860 5585);
DISPLAY 0.680851 (-3860 5585);
WIRE 16 -1 (-2975 3200)(-2975 2750);
WIRE 16 -1 (-2350 2750)(-2975 2750);
WIRE 16 -1 (-2975 2750)(-3100 2750);
FORCEPROP 2 LAST SIG_NAME SMB_USB_CPU0_HUB1_SDA_R2
J 0
(-3010 2760);
DISPLAY 0.553191 (-3010 2760);
FORCEPROP 2 LASTPROP $XRERR UNIQUE?
J 0
(-3250 2760);
DISPLAY 0.638298 (-3250 2760);
PAINT MONO (-3250 2760);
DISPLAY INVISIBLE (-3250 2760);
WIRE 16 -1 (-2900 3200)(-2900 2800);
WIRE 16 -1 (-2350 2800)(-2900 2800);
WIRE 16 -1 (-2900 2800)(-3100 2800);
FORCEPROP 2 LAST SIG_NAME SMB_USB_CPU0_HUB1_SCL_R2
J 0
(-3010 2810);
DISPLAY 0.553191 (-3010 2810);
FORCEPROP 2 LASTPROP $XRERR UNIQUE?
J 0
(-3250 2810);
DISPLAY 0.638298 (-3250 2810);
PAINT MONO (-3250 2810);
DISPLAY INVISIBLE (-3250 2810);
WIRE 16 -1 (-2350 2850)(-2700 2850);
FORCEPROP 2 LAST SIG_NAME PD_USB_CPU0_WP
J 0
(-2885 2860);
DISPLAY 0.680851 (-2885 2860);
FORCEPROP 2 LASTPROP $XRERR UNIQUE?
J 0
(-3125 2860);
DISPLAY 0.638298 (-3125 2860);
PAINT MONO (-3125 2860);
DISPLAY INVISIBLE (-3125 2860);
WIRE 16 -1 (-2700 2850)(-2700 2525);
WIRE 16 -1 (-450 2475)(-450 2800);
WIRE 16 -1 (-450 2800)(-450 3100);
WIRE 16 -1 (-1750 2800)(-450 2800);
FORCEPROP 2 LAST SIG_NAME USB_CPU0_ADD_A2
J 0
(-1685 2810);
DISPLAY 0.680851 (-1685 2810);
FORCEPROP 2 LASTPROP $XRERR UNIQUE?
J 0
(-1925 2810);
DISPLAY 0.638298 (-1925 2810);
PAINT MONO (-1925 2810);
DISPLAY INVISIBLE (-1925 2810);
WIRE 16 -1 (-850 2475)(-850 2850);
WIRE 16 -1 (-850 2850)(-850 3100);
WIRE 16 -1 (-1750 2850)(-850 2850);
FORCEPROP 2 LAST SIG_NAME USB_CPU0_ADD_A1
J 0
(-1685 2860);
DISPLAY 0.680851 (-1685 2860);
FORCEPROP 2 LASTPROP $XRERR UNIQUE?
J 0
(-1925 2860);
DISPLAY 0.638298 (-1925 2860);
PAINT MONO (-1925 2860);
DISPLAY INVISIBLE (-1925 2860);
WIRE 16 -1 (-1050 2900)(-1050 3125);
WIRE 16 -1 (-1050 2900)(-1050 2500);
WIRE 16 -1 (-1750 2900)(-1050 2900);
FORCEPROP 2 LAST SIG_NAME USB_CPU0_ADD_A0
J 0
(-1685 2910);
DISPLAY 0.680851 (-1685 2910);
FORCEPROP 2 LASTPROP $XRERR UNIQUE?
J 0
(-1925 2910);
DISPLAY 0.638298 (-1925 2910);
PAINT MONO (-1925 2910);
DISPLAY INVISIBLE (-1925 2910);
WIRE 16 -1 (-3300 2800)(-3775 2800);
FORCEPROP 2 LAST SIG_NAME SMB_USB_CPU0_HUB1_SCL
J 0
(-3785 2810);
DISPLAY 0.446809 (-3785 2810);
WIRE 16 -1 (-5275 3025)(-7175 3025);
FORCEPROP 2 LAST SIG_NAME PU_CPU0_USB_HUB_PWR_EN
J 0
(-6435 3035);
DISPLAY 0.680851 (-6435 3035);
FORCEPROP 2 LASTPROP $XRERR UNIQUE?
J 0
(-6675 3035);
DISPLAY 0.638298 (-6675 3035);
PAINT MONO (-6675 3035);
DISPLAY INVISIBLE (-6675 3035);
WIRE 16 -1 (-7175 3025)(-7175 3175);
WIRE 16 -1 (-5275 2925)(-7475 2925);
FORCEPROP 2 LAST SIG_NAME PU_CPU0_USB_HUB_OVRCURR
J 0
(-6410 2935);
DISPLAY 0.680851 (-6410 2935);
FORCEPROP 2 LASTPROP $XRERR UNIQUE?
J 0
(-6650 2935);
DISPLAY 0.638298 (-6650 2935);
PAINT MONO (-6650 2935);
DISPLAY INVISIBLE (-6650 2935);
WIRE 16 -1 (-7475 2925)(-7475 3175);
WIRE 16 -1 (-5275 2675)(-8100 2675);
FORCEPROP 2 LAST SIG_NAME PU_CPU0_USB_HUB_RESERVED1
J 0
(-6385 2685);
DISPLAY 0.680851 (-6385 2685);
FORCEPROP 2 LASTPROP $XRERR UNIQUE?
J 0
(-6625 2685);
DISPLAY 0.638298 (-6625 2685);
PAINT MONO (-6625 2685);
DISPLAY INVISIBLE (-6625 2685);
WIRE 16 -1 (-8100 2675)(-8100 3175);
WIRE 16 -1 (-7425 4425)(-5275 4425);
FORCEPROP 2 LAST SIG_NAME SMB_USB_CPU0_HUB1_SCL
J 0
(-6260 4460);
DISPLAY 0.680851 (-6260 4460);
WIRE 16 -1 (-3050 5425)(-4025 5425);
FORCEPROP 2 LAST SIG_NAME USB3_CPU0_BMC_HUB1_TX_DP
J 0
(-3885 5435);
DISPLAY 0.680851 (-3885 5435);
WIRE 16 -1 (-4025 6125)(-2925 6125);
FORCEPROP 2 LAST SIG_NAME USB_CPU0_HUB1_VBUS_DS
J 0
(-3885 6135);
DISPLAY 0.680851 (-3885 6135);
FORCEPROP 2 LASTPROP $XRERR UNIQUE?
J 0
(-4125 6135);
DISPLAY 0.638298 (-4125 6135);
PAINT MONO (-4125 6135);
DISPLAY INVISIBLE (-4125 6135);
WIRE 16 -1 (-8000 2375)(-5275 2375);
FORCEPROP 2 LAST SIG_NAME XTAL_USB_CPU0_HUB1_XOUT
J 0
(-6710 2385);
DISPLAY 0.680851 (-6710 2385);
FORCEPROP 2 LASTPROP $XRERR UNIQUE?
J 0
(-6950 2385);
DISPLAY 0.638298 (-6950 2385);
PAINT MONO (-6950 2385);
DISPLAY INVISIBLE (-6950 2385);
WIRE 16 -1 (-8000 1750)(-8000 2375);
WIRE 16 -1 (-7275 1750)(-8000 1750);
WIRE 16 -1 (-8000 1650)(-8000 1750);
WIRE 16 -1 (-5275 4125)(-6925 4125);
FORCEPROP 2 LAST SIG_NAME USB_CPU0_HUB1_RREF_USB2
J 0
(-6210 4135);
DISPLAY 0.680851 (-6210 4135);
FORCEPROP 2 LASTPROP $XRERR UNIQUE?
J 0
(-6450 4135);
DISPLAY 0.638298 (-6450 4135);
PAINT MONO (-6450 4135);
DISPLAY INVISIBLE (-6450 4135);
WIRE 16 -1 (-5275 4225)(-6900 4225);
FORCEPROP 2 LAST SIG_NAME USB_CPU0_HUB1_RREF_SS
J 0
(-6235 4235);
DISPLAY 0.680851 (-6235 4235);
FORCEPROP 2 LASTPROP $XRERR UNIQUE?
J 0
(-6475 4235);
DISPLAY 0.638298 (-6475 4235);
PAINT MONO (-6475 4235);
DISPLAY INVISIBLE (-6475 4235);
WIRE 16 -1 (-5275 4525)(-7400 4525);
FORCEPROP 2 LAST SIG_NAME SMB_USB_CPU0_HUB1_SDA
J 0
(-6260 4560);
DISPLAY 0.680851 (-6260 4560);
WIRE 16 -1 (-5275 5575)(-6250 5575);
FORCEPROP 2 LAST SIG_NAME USB3_CPU0_BMC_RX_HUB1_DP
J 0
(-6160 5585);
DISPLAY 0.680851 (-6160 5585);
WIRE 16 -1 (-8525 600)(-7550 600);
FORCEPROP 2 LAST SIG_NAME RST_USB_HUB_N
J 0
(-8435 635);
DISPLAY 0.680851 (-8435 635);
WIRE 16 -1 (-5275 3575)(-6375 3575);
FORCEPROP 2 LAST SIG_NAME TP_CPU0_USB_HUB1_SUSPEND
J 0
(-6185 3585);
DISPLAY 0.680851 (-6185 3585);
FORCEPROP 2 LASTPROP $XRERR UNIQUE?
J 0
(-6615 3575);
DISPLAY 0.638298 (-6615 3575);
PAINT MONO (-6615 3575);
DISPLAY INVISIBLE (-6615 3575);
WIRE 16 -1 (-5275 5425)(-6250 5425);
FORCEPROP 2 LAST SIG_NAME USB3_CPU0_BMC_TX_C1_DP
J 0
(-6160 5435);
DISPLAY 0.680851 (-6160 5435);
WIRE 16 -1 (-5275 5475)(-6250 5475);
FORCEPROP 2 LAST SIG_NAME USB3_CPU0_BMC_TX_C1_DN
J 0
(-6185 5485);
DISPLAY 0.680851 (-6185 5485);
WIRE 16 -1 (-5275 5625)(-6250 5625);
FORCEPROP 2 LAST SIG_NAME USB3_CPU0_BMC_RX_HUB1_DN
J 0
(-6160 5635);
DISPLAY 0.680851 (-6160 5635);
WIRE 16 -1 (-5275 5725)(-6225 5725);
FORCEPROP 2 LAST SIG_NAME USB2_CPU0_P0_R1_DP
J 0
(-6110 5735);
DISPLAY 0.680851 (-6110 5735);
WIRE 16 -1 (-5275 5775)(-6225 5775);
FORCEPROP 2 LAST SIG_NAME USB2_CPU0_P0_R1_DN
J 0
(-6110 5785);
DISPLAY 0.680851 (-6110 5785);
WIRE 16 -1 (-5275 6125)(-7025 6125);
FORCEPROP 2 LAST SIG_NAME USB_CPU0_HUB1_VBUS_US
J 0
(-6435 6135);
DISPLAY 0.680851 (-6435 6135);
FORCEPROP 2 LASTPROP $XRERR UNIQUE?
J 0
(-6675 6135);
DISPLAY 0.638298 (-6675 6135);
PAINT MONO (-6675 6135);
DISPLAY INVISIBLE (-6675 6135);
WIRE 16 -1 (-7025 6200)(-7025 6125);
WIRE 16 -1 (-7025 6125)(-7025 5900);
WIRE 16 -1 (-3050 5475)(-4025 5475);
FORCEPROP 2 LAST SIG_NAME USB3_CPU0_BMC_HUB1_TX_DN
J 0
(-3885 5485);
DISPLAY 0.680851 (-3885 5485);
DOT 1 (-3300 975);
DOT 1 (-3100 1400);
DOT 1 (-850 2050);
DOT 1 (-850 2850);
DOT 1 (-850 3650);
DOT 1 (-1050 2900);
DOT 1 (-2975 2750);
DOT 1 (-2900 2800);
DOT 1 (-1050 3650);
DOT 1 (-1050 2050);
DOT 1 (-2850 925);
DOT 1 (-6350 1750);
DOT 1 (-1525 6300);
DOT 1 (-8000 1275);
DOT 1 (-5875 200);
DOT 1 (-8000 1750);
DOT 1 (-7650 3650);
DOT 1 (-2425 3500);
DOT 1 (-450 2800);
DOT 1 (-7025 6125);
DOT 1 (-3800 1275);
DOT 1 (-6350 600);
DOT 1 (-7725 4125);
CIRCLE (-7950 5600)(-7700 5600);
PAINT YELLOW (-7950 5600);
DOT 1 (-7775 3650);
DOT 1 (-7475 3650);
DOT 1 (-6350 1225);
DOT 1 (-6875 600);
DOT 1 (-5875 600);
DOT 1 (-1075 5650);
DOT 1 (-2650 3500);
DOT 1 (-2900 3500);
FORCENOTE
ADDRESS : 0XA2 (8-BIT) / 0X51 (7-BIT)
(-3200 3725) 0;
DISPLAY LEFT (-3200 3725);
DISPLAY 1.021277 (-3200 3725);
PAINT SKYBLUE (-3200 3725);
FORCENOTE
TBC
(-8025 5575) 0;
DISPLAY LEFT (-8025 5575);
DISPLAY 1.276596 (-8025 5575);
FORCENOTE
$CDS_IMAGE|clipboard_0_30.jpg|1706|782
(-1500 950) 0;
DISPLAY LEFT (-1500 950);
FORCENOTE
$CDS_IMAGE|clipboard_0_31.jpg|1773|354
(-2325 4000) 0;
DISPLAY LEFT (-2325 4000);
QUIT
